FILE_TYPE = MACRO_DRAWING;
SET COLOR_WIRE YELLOW;
SET COLOR_PROP ORANGE;
SET COLOR_DOT WHITE;
SET COLOR_ARC YELLOW;
SET COLOR_BODY GREEN;
SET COLOR_NOTE PURPLE;
SET PROP_DISPLAY VALUE;
SET PAGE_NUMBER P195;
FORCEADD Q_CAP..1
(775 1850);
FORCEPROP 1 LAST LOCATION PC136_6
J 0
(825 1950);
DISPLAY 0.489362 (825 1950);
PAINT SKYBLUE (825 1950);
FORCEPROP 0 LAST $SEC 1
J 0
(825 1975);
DISPLAY 0.680851 (825 1975);
PAINT MONO (825 1975);
DISPLAY INVISIBLE (825 1975);
FORCEPROP 0 LAST CDS_SEC 1
J 0
(1025 1900);
DISPLAY 1.021277 (1025 1900);
DISPLAY INVISIBLE (1025 1900);
FORCEPROP 1 LASTPIN (775 1950) $PN 1
J 0
(785 1930);
DISPLAY 0.489362 (785 1930);
PAINT MONO (785 1930);
FORCEPROP 1 LASTPIN (775 1750) $PN 2
J 0
(785 1730);
DISPLAY 0.489362 (785 1730);
PAINT MONO (785 1730);
FORCEPROP 1 LAST MATERIAL X7R
J 0
(825 1750);
DISPLAY 0.489362 (825 1750);
PAINT SKYBLUE (825 1750);
FORCEPROP 1 LAST TOLERANCE 10%
J 0
(825 1800);
DISPLAY 0.489362 (825 1800);
PAINT SKYBLUE (825 1800);
FORCEPROP 1 LAST VALUE 0.1UF
J 0
(825 1900);
DISPLAY 0.489362 (825 1900);
PAINT SKYBLUE (825 1900);
FORCEPROP 1 LAST VOLTAGE 25V
J 0
(825 1850);
DISPLAY 0.489362 (825 1850);
PAINT SKYBLUE (825 1850);
FORCEPROP 1 LAST PACK_TYPE 0402
J 0
(825 1650);
DISPLAY 0.489362 (825 1650);
PAINT SKYBLUE (825 1650);
FORCEPROP 2 LAST CDS_LIB pure_quanta
J 0
(775 1850);
DISPLAY INVISIBLE (775 1850);
FORCEPROP 1 LAST PATH I1
J 0
(825 2000);
DISPLAY 0.978723 (825 2000);
PAINT WHITE (825 2000);
DISPLAY INVISIBLE (825 2000);
FORCEPROP 1 LAST PART_NUMBER CH4104K1B00
J 0
(825 1700);
DISPLAY 0.489362 (825 1700);
PAINT SKYBLUE (825 1700);
DISPLAY INVISIBLE (825 1700);
FORCEADD Q_CAP..1
(725 4475);
FORCEPROP 1 LAST LOCATION PC422_5
J 0
(775 4575);
DISPLAY 0.489362 (775 4575);
PAINT SKYBLUE (775 4575);
FORCEPROP 0 LAST $SEC 1
J 0
(775 4600);
DISPLAY 0.680851 (775 4600);
PAINT MONO (775 4600);
DISPLAY INVISIBLE (775 4600);
FORCEPROP 0 LAST CDS_SEC 1
J 0
(975 4525);
DISPLAY 1.021277 (975 4525);
DISPLAY INVISIBLE (975 4525);
FORCEPROP 1 LASTPIN (725 4575) $PN 1
J 0
(735 4555);
DISPLAY 0.489362 (735 4555);
PAINT MONO (735 4555);
FORCEPROP 1 LASTPIN (725 4375) $PN 2
J 0
(735 4355);
DISPLAY 0.489362 (735 4355);
PAINT MONO (735 4355);
FORCEPROP 1 LAST MATERIAL X7R
J 0
(775 4375);
DISPLAY 0.489362 (775 4375);
PAINT SKYBLUE (775 4375);
FORCEPROP 1 LAST TOLERANCE 10%
J 0
(775 4425);
DISPLAY 0.489362 (775 4425);
PAINT SKYBLUE (775 4425);
FORCEPROP 1 LAST VALUE 0.1UF
J 0
(775 4525);
DISPLAY 0.489362 (775 4525);
PAINT SKYBLUE (775 4525);
FORCEPROP 1 LAST VOLTAGE 25V
J 0
(775 4475);
DISPLAY 0.489362 (775 4475);
PAINT SKYBLUE (775 4475);
FORCEPROP 1 LAST PACK_TYPE 0402
J 0
(775 4275);
DISPLAY 0.489362 (775 4275);
PAINT SKYBLUE (775 4275);
FORCEPROP 2 LAST CDS_LIB pure_quanta
J 0
(725 4475);
DISPLAY INVISIBLE (725 4475);
FORCEPROP 1 LAST PATH I10
J 0
(775 4625);
DISPLAY 0.978723 (775 4625);
PAINT WHITE (775 4625);
DISPLAY INVISIBLE (775 4625);
FORCEPROP 1 LAST PART_NUMBER CH4104K1B00
J 0
(775 4325);
DISPLAY 0.489362 (775 4325);
PAINT SKYBLUE (775 4325);
DISPLAY INVISIBLE (775 4325);
FORCEADD UNIVERSAL_GND..1
(1725 2450);
FORCEPROP 3 LASTPIN (1725 2500) SIG_NAME GND\g
J 0
(1735 2510);
DISPLAY 0.659574 (1735 2510);
PAINT MONO (1735 2510);
DISPLAY INVISIBLE (1735 2510);
FORCEPROP 2 LAST CDS_LIB pure_quanta_power
J 0
(1725 2450);
DISPLAY INVISIBLE (1725 2450);
FORCEPROP 1 LAST HDL_POWER GND
J 1
(1750 2375);
DISPLAY 0.872340 (1750 2375);
PAINT GREEN (1750 2375);
DISPLAY INVISIBLE (1750 2375);
FORCEPROP 1 LAST PATH I11
J 0
(1800 2450);
DISPLAY 0.872340 (1800 2450);
PAINT AQUA (1800 2450);
DISPLAY INVISIBLE (1800 2450);
FORCEADD Q_CAP..1
(1725 2650);
FORCEPROP 1 LAST LOCATION PC138
J 0
(1775 2750);
DISPLAY 0.489362 (1775 2750);
PAINT SKYBLUE (1775 2750);
FORCEPROP 0 LAST $SEC 1
J 0
(1775 2800);
DISPLAY 0.680851 (1775 2800);
PAINT MONO (1775 2800);
DISPLAY INVISIBLE (1775 2800);
FORCEPROP 0 LAST CDS_SEC 1
J 0
(1775 2800);
DISPLAY 1.021277 (1775 2800);
DISPLAY INVISIBLE (1775 2800);
FORCEPROP 1 LASTPIN (1725 2750) $PN 1
J 0
(1735 2730);
DISPLAY 0.489362 (1735 2730);
PAINT MONO (1735 2730);
FORCEPROP 1 LASTPIN (1725 2550) $PN 2
J 0
(1735 2530);
DISPLAY 0.489362 (1735 2530);
PAINT MONO (1735 2530);
FORCEPROP 1 LAST MATERIAL X6S
J 0
(1775 2550);
DISPLAY 0.489362 (1775 2550);
PAINT SKYBLUE (1775 2550);
FORCEPROP 1 LAST TOLERANCE 10%
J 0
(1775 2600);
DISPLAY 0.489362 (1775 2600);
PAINT SKYBLUE (1775 2600);
FORCEPROP 1 LAST VALUE 2.2UF
J 0
(1775 2700);
DISPLAY 0.489362 (1775 2700);
PAINT SKYBLUE (1775 2700);
FORCEPROP 1 LAST VOLTAGE 10V
J 0
(1775 2650);
DISPLAY 0.489362 (1775 2650);
PAINT SKYBLUE (1775 2650);
FORCEPROP 1 LAST PACK_TYPE C0402
J 0
(1775 2450);
DISPLAY 0.489362 (1775 2450);
PAINT SKYBLUE (1775 2450);
FORCEPROP 2 LAST CDS_LIB pure_quanta
J 0
(1725 2650);
DISPLAY INVISIBLE (1725 2650);
FORCEPROP 1 LAST PATH I12
J 0
(1775 2800);
DISPLAY 0.978723 (1775 2800);
PAINT WHITE (1775 2800);
DISPLAY INVISIBLE (1775 2800);
FORCEPROP 1 LAST PART_NUMBER CH5222KEB01
J 0
(1775 2500);
DISPLAY 0.489362 (1775 2500);
PAINT SKYBLUE (1775 2500);
DISPLAY INVISIBLE (1775 2500);
FORCEADD Q_RES..2
(1725 3200);
FORCEPROP 1 LAST LOCATION PR427
J 0
(1770 3325);
DISPLAY 0.489362 (1770 3325);
PAINT SKYBLUE (1770 3325);
FORCEPROP 0 LAST $SEC 1
J 0
(1775 3375);
DISPLAY 0.680851 (1775 3375);
PAINT MONO (1775 3375);
DISPLAY INVISIBLE (1775 3375);
FORCEPROP 0 LAST CDS_SEC 1
J 0
(1775 3375);
DISPLAY 1.021277 (1775 3375);
DISPLAY INVISIBLE (1775 3375);
FORCEPROP 1 LASTPIN (1725 3300) $PN 1
J 0
(1730 3262);
DISPLAY 0.489362 (1730 3262);
PAINT MONO (1730 3262);
FORCEPROP 1 LASTPIN (1725 3100) $PN 2
J 0
(1730 3110);
DISPLAY 0.489362 (1730 3110);
PAINT MONO (1730 3110);
FORCEPROP 1 LAST PACK_TYPE 0402LF
J 0
(1775 3025);
DISPLAY 0.489362 (1775 3025);
PAINT SKYBLUE (1775 3025);
FORCEPROP 1 LAST VALUE 2.2
J 0
(1775 3275);
DISPLAY 0.489362 (1775 3275);
PAINT SKYBLUE (1775 3275);
FORCEPROP 1 LAST TOLERANCE 1%
J 0
(1775 3225);
DISPLAY 0.489362 (1775 3225);
PAINT SKYBLUE (1775 3225);
FORCEPROP 1 LAST MATERIAL CHIP
J 0
(1775 3125);
DISPLAY 0.489362 (1775 3125);
PAINT SKYBLUE (1775 3125);
FORCEPROP 1 LAST WATTAGE 1/16W
J 0
(1775 3175);
DISPLAY 0.489362 (1775 3175);
PAINT SKYBLUE (1775 3175);
FORCEPROP 2 LAST CDS_LIB pure_quanta
J 0
(1725 3200);
DISPLAY INVISIBLE (1725 3200);
FORCEPROP 1 LAST PATH I13
J 0
(1775 3375);
DISPLAY 0.978723 (1775 3375);
PAINT WHITE (1775 3375);
DISPLAY INVISIBLE (1775 3375);
FORCEPROP 1 LAST PART_NUMBER CS-2202FB01
J 0
(1775 3075);
DISPLAY 0.489362 (1775 3075);
PAINT SKYBLUE (1775 3075);
DISPLAY INVISIBLE (1775 3075);
FORCEADD UNIVERSAL_GND..1
(1225 4125);
FORCEPROP 3 LASTPIN (1225 4175) SIG_NAME GND\g
J 0
(1235 4185);
DISPLAY 0.659574 (1235 4185);
PAINT MONO (1235 4185);
DISPLAY INVISIBLE (1235 4185);
FORCEPROP 2 LAST CDS_LIB pure_quanta_power
J 0
(1225 4125);
PAINT MONO (1225 4125);
DISPLAY INVISIBLE (1225 4125);
FORCEPROP 1 LAST HDL_POWER GND
J 1
(1250 4050);
DISPLAY 0.872340 (1250 4050);
PAINT GREEN (1250 4050);
DISPLAY INVISIBLE (1250 4050);
FORCEPROP 1 LAST PATH I14
J 0
(1300 4125);
DISPLAY 0.872340 (1300 4125);
PAINT AQUA (1300 4125);
DISPLAY INVISIBLE (1300 4125);
FORCEADD Q_RES..2
R 2
(1225 4350);
FORCEPROP 1 LAST LOCATION PR270
J 2
(1180 4475);
DISPLAY 0.489362 (1180 4475);
PAINT SKYBLUE (1180 4475);
FORCEPROP 0 LAST $SEC 1
J 0
(1200 4525);
DISPLAY 0.680851 (1200 4525);
PAINT MONO (1200 4525);
DISPLAY INVISIBLE (1200 4525);
FORCEPROP 0 LAST CDS_SEC 1
J 0
(1200 4525);
DISPLAY 1.021277 (1200 4525);
DISPLAY INVISIBLE (1200 4525);
FORCEPROP 1 LASTPIN (1225 4450) $PN 1
J 2
(1220 4412);
DISPLAY 0.489362 (1220 4412);
PAINT MONO (1220 4412);
FORCEPROP 1 LASTPIN (1225 4250) $PN 2
J 2
(1220 4260);
DISPLAY 0.489362 (1220 4260);
PAINT MONO (1220 4260);
FORCEPROP 1 LAST WATTAGE 1/16W
J 2
(1185 4325);
DISPLAY 0.489362 (1185 4325);
PAINT SKYBLUE (1185 4325);
FORCEPROP 1 LAST MATERIAL EMPTY
J 2
(1185 4275);
DISPLAY 0.489362 (1185 4275);
PAINT RED (1185 4275);
FORCEPROP 1 LAST TOLERANCE 1%
J 2
(1180 4375);
DISPLAY 0.489362 (1180 4375);
PAINT SKYBLUE (1180 4375);
FORCEPROP 1 LAST VALUE 8.87K
J 2
(1180 4425);
DISPLAY 0.489362 (1180 4425);
PAINT SKYBLUE (1180 4425);
FORCEPROP 1 LAST PACK_TYPE 0402LF
J 2
(1185 4175);
DISPLAY 0.489362 (1185 4175);
PAINT SKYBLUE (1185 4175);
FORCEPROP 2 LAST CDS_LIB pure_quanta
J 2
(1225 4350);
DISPLAY INVISIBLE (1225 4350);
FORCEPROP 1 LAST PATH I15
J 2
(1175 4525);
DISPLAY 0.978723 (1175 4525);
PAINT WHITE (1175 4525);
DISPLAY INVISIBLE (1175 4525);
FORCEPROP 1 LAST PART_NUMBER CS28872FB01
J 2
(1185 4225);
DISPLAY 0.489362 (1185 4225);
PAINT SKYBLUE (1185 4225);
DISPLAY INVISIBLE (1185 4225);
FORCEADD VCC_CORE..1
(1725 3600);
FORCEPROP 3 LASTPIN (1725 3550) SIG_NAME PVDDCR_CPU1_P1_PVCC\g
J 0
(1735 3560);
DISPLAY 0.659574 (1735 3560);
PAINT MONO (1735 3560);
DISPLAY INVISIBLE (1735 3560);
FORCEPROP 1 LAST HDL_POWER PVDDCR_CPU1_P1_PVCC
J 1
(1725 3650);
DISPLAY 0.489362 (1725 3650);
PAINT GREEN (1725 3650);
FORCEPROP 2 LAST CDS_LIB pure_quanta_power
J 0
(1725 3600);
DISPLAY INVISIBLE (1725 3600);
FORCEPROP 1 LAST PATH I16
J 0
(1775 3625);
DISPLAY 0.872340 (1775 3625);
PAINT AQUA (1775 3625);
DISPLAY INVISIBLE (1775 3625);
FORCEADD OFFPAGE..5
(1700 4350);
FORCEPROP 2 LAST $XR3 217 
J 0
(1445 4422);
DISPLAY 0.638298 (1445 4422);
PAINT MONO (1445 4422);
FORCEPROP 2 LAST $XR2 220 
J 0
(1445 4386);
DISPLAY 0.638298 (1445 4386);
PAINT MONO (1445 4386);
FORCEPROP 2 LAST $XR1 219 
J 0
(1445 4314);
DISPLAY 0.638298 (1445 4314);
PAINT MONO (1445 4314);
FORCEPROP 2 LAST $XR0 218 
J 0
(1445 4350);
DISPLAY 0.638298 (1445 4350);
PAINT MONO (1445 4350);
FORCEPROP 2 LAST CDS_LIB standard
J 0
(1700 4350);
DISPLAY INVISIBLE (1700 4350);
FORCEPROP 1 LAST OFFPAGE TRUE
J 0
(2025 4225);
DISPLAY 0.872340 (2025 4225);
PAINT GREEN (2025 4225);
DISPLAY INVISIBLE (2025 4225);
FORCEPROP 1 LAST COMMENT_BODY TRUE
J 0
(1800 4275);
DISPLAY 0.872340 (1800 4275);
PAINT GREEN (1800 4275);
DISPLAY INVISIBLE (1800 4275);
FORCEPROP 2 LAST PATH I17
J 0
(1425 4475);
DISPLAY 0.680851 (1425 4475);
DISPLAY INVISIBLE (1425 4475);
FORCEADD OFFPAGE..1
(1700 4250);
FORCEPROP 2 LAST $XR0 217 
J 0
(1418 4250);
DISPLAY 0.638298 (1418 4250);
PAINT MONO (1418 4250);
FORCEPROP 2 LAST CDS_LIB standard
J 0
(1700 4250);
DISPLAY INVISIBLE (1700 4250);
FORCEPROP 1 LAST OFFPAGE TRUE
J 0
(2025 4125);
DISPLAY 0.872340 (2025 4125);
PAINT GREEN (2025 4125);
DISPLAY INVISIBLE (2025 4125);
FORCEPROP 1 LAST COMMENT_BODY TRUE
J 0
(1825 4150);
DISPLAY 0.872340 (1825 4150);
PAINT GREEN (1825 4150);
DISPLAY INVISIBLE (1825 4150);
FORCEPROP 2 LAST PATH I18
J 0
(1450 4300);
DISPLAY 0.680851 (1450 4300);
DISPLAY INVISIBLE (1450 4300);
FORCEADD ISL99390FRZTR5935..1
(3200 2225);
FORCEPROP 1 LAST LOCATION PU33
J 0
(2900 3100);
DISPLAY 0.489362 (2900 3100);
PAINT SKYBLUE (2900 3100);
FORCEPROP 2 LAST $SEC 1
J 0
(2900 3275);
DISPLAY 0.680851 (2900 3275);
PAINT MONO (2900 3275);
DISPLAY INVISIBLE (2900 3275);
FORCEPROP 2 LAST CDS_SEC 1
J 0
(2900 3275);
DISPLAY 1.021277 (2900 3275);
DISPLAY INVISIBLE (2900 3275);
FORCEPROP 2 LASTPIN (3600 1775) $PN 2
J 0
(3610 1785);
DISPLAY 0.489362 (3610 1785);
PAINT MONO (3610 1785);
FORCEPROP 2 LASTPIN (3600 2575) $PN 33
J 0
(3610 2585);
DISPLAY 0.489362 (3610 2585);
PAINT MONO (3610 2585);
FORCEPROP 2 LASTPIN (2750 1975) $PN 31
J 2
(2740 1985);
DISPLAY 0.489362 (2740 1985);
PAINT MONO (2740 1985);
FORCEPROP 2 LASTPIN (2750 2375) $PN 35
J 2
(2740 2385);
DISPLAY 0.489362 (2740 2385);
PAINT MONO (2740 2385);
FORCEPROP 2 LASTPIN (3600 1925) $PN 6
J 0
(3610 1935);
DISPLAY 0.489362 (3610 1935);
PAINT MONO (3610 1935);
FORCEPROP 2 LASTPIN (3600 1875) $PN 41
J 0
(3610 1885);
DISPLAY 0.489362 (3610 1885);
PAINT MONO (3610 1885);
FORCEPROP 2 LASTPIN (2750 2225) $PN 38
J 2
(2740 2235);
DISPLAY 0.489362 (2740 2235);
PAINT MONO (2740 2235);
FORCEPROP 2 LASTPIN (2750 1925) $PN 37
J 2
(2740 1935);
DISPLAY 0.489362 (2740 1935);
PAINT MONO (2740 1935);
FORCEPROP 2 LASTPIN (3600 1725) $PN 5
J 0
(3610 1735);
DISPLAY 0.489362 (3610 1735);
PAINT MONO (3610 1735);
FORCEPROP 2 LASTPIN (3600 1675) $PN 7_9-20_24
J 0
(3610 1685);
DISPLAY 0.489362 (3610 1685);
PAINT MONO (3610 1685);
FORCEPROP 2 LASTPIN (3600 1625) $PN 40
J 0
(3610 1635);
DISPLAY 0.489362 (3610 1635);
PAINT MONO (3610 1635);
FORCEPROP 2 LASTPIN (3600 2325) $PN 32
J 0
(3610 2335);
DISPLAY 0.489362 (3610 2335);
PAINT MONO (3610 2335);
FORCEPROP 2 LASTPIN (2750 2875) $PN 4
J 2
(2740 2885);
DISPLAY 0.489362 (2740 2885);
PAINT MONO (2740 2885);
FORCEPROP 2 LASTPIN (2750 1625) $PN 34
J 2
(2740 1635);
DISPLAY 0.489362 (2740 1635);
PAINT MONO (2740 1635);
FORCEPROP 2 LASTPIN (2750 2125) $PN 39
J 2
(2740 2135);
DISPLAY 0.489362 (2740 2135);
PAINT MONO (2740 2135);
FORCEPROP 2 LASTPIN (3600 2225) $PN 10_19
J 0
(3610 2235);
DISPLAY 0.489362 (3610 2235);
PAINT MONO (3610 2235);
FORCEPROP 2 LASTPIN (2750 1725) $PN 36
J 2
(2740 1735);
DISPLAY 0.489362 (2740 1735);
PAINT MONO (2740 1735);
FORCEPROP 2 LASTPIN (2750 2575) $PN 3
J 2
(2740 2585);
DISPLAY 0.489362 (2740 2585);
PAINT MONO (2740 2585);
FORCEPROP 2 LASTPIN (3600 2875) $PN 25_29
J 0
(3610 2885);
DISPLAY 0.489362 (3610 2885);
PAINT MONO (3610 2885);
FORCEPROP 2 LASTPIN (3600 2825) $PN 30
J 0
(3610 2835);
DISPLAY 0.489362 (3610 2835);
PAINT MONO (3610 2835);
FORCEPROP 2 LASTPIN (3600 1975) $PN 1
J 0
(3610 1985);
DISPLAY 0.489362 (3610 1985);
PAINT MONO (3610 1985);
FORCEPROP 2 LAST VALUE ISL99390FRZ-TR5935
J 0
(2900 3200);
DISPLAY 0.489362 (2900 3200);
PAINT SKYBLUE (2900 3200);
FORCEPROP 2 LAST PART_TYPE SMLF
J 0
(2900 3250);
DISPLAY 0.638298 (2900 3250);
FORCEPROP 1 LAST MATERIAL IC
J 0
(2900 2950);
DISPLAY 0.489362 (2900 2950);
PAINT SKYBLUE (2900 2950);
FORCEPROP 1 LAST NEEDS_NO_SIZE TRUE
J 0
(3200 2225);
DISPLAY 0.723404 (3200 2225);
PAINT GREEN (3200 2225);
DISPLAY INVISIBLE (3200 2225);
FORCEPROP 1 LAST CDS_LMAN_SYM_OUTLINE -300,700,250,-650
J 0
(3200 2225);
DISPLAY 0.468085 (3200 2225);
PAINT GREEN (3200 2225);
DISPLAY INVISIBLE (3200 2225);
FORCEPROP 2 LAST CDS_LIB pure_quanta
J 0
(3200 2225);
DISPLAY INVISIBLE (3200 2225);
FORCEPROP 1 LAST PATH I19
J 0
(3200 2225);
DISPLAY 0.723404 (3200 2225);
PAINT GREEN (3200 2225);
DISPLAY INVISIBLE (3200 2225);
FORCEPROP 1 LAST PART_NUMBER AL099390004
J 0
(2900 3025);
DISPLAY 0.489362 (2900 3025);
PAINT SKYBLUE (2900 3025);
DISPLAY INVISIBLE (2900 3025);
FORCEADD UNIVERSAL_GND..1
(775 1650);
FORCEPROP 3 LASTPIN (775 1700) SIG_NAME GND\g
J 0
(785 1710);
DISPLAY 0.659574 (785 1710);
PAINT MONO (785 1710);
DISPLAY INVISIBLE (785 1710);
FORCEPROP 2 LAST CDS_LIB pure_quanta_power
J 0
(775 1650);
DISPLAY INVISIBLE (775 1650);
FORCEPROP 1 LAST HDL_POWER GND
J 1
(800 1575);
DISPLAY 0.872340 (800 1575);
PAINT GREEN (800 1575);
DISPLAY INVISIBLE (800 1575);
FORCEPROP 1 LAST PATH I2
J 0
(850 1650);
DISPLAY 0.872340 (850 1650);
PAINT AQUA (850 1650);
DISPLAY INVISIBLE (850 1650);
FORCEADD UNIVERSAL_GND..1
(3850 1500);
FORCEPROP 3 LASTPIN (3850 1550) SIG_NAME GND\g
J 0
(3860 1560);
DISPLAY 0.659574 (3860 1560);
PAINT MONO (3860 1560);
DISPLAY INVISIBLE (3860 1560);
FORCEPROP 2 LAST CDS_LIB pure_quanta_power
J 0
(3850 1500);
PAINT MONO (3850 1500);
DISPLAY INVISIBLE (3850 1500);
FORCEPROP 1 LAST HDL_POWER GND
J 1
(3875 1425);
DISPLAY 0.872340 (3875 1425);
PAINT GREEN (3875 1425);
DISPLAY INVISIBLE (3875 1425);
FORCEPROP 1 LAST PATH I20
J 0
(3925 1500);
DISPLAY 0.872340 (3925 1500);
PAINT AQUA (3925 1500);
DISPLAY INVISIBLE (3925 1500);
FORCEADD UNIVERSAL_GND..1
(2075 2950);
FORCEPROP 3 LASTPIN (2075 3000) SIG_NAME GND\g
J 0
(2085 3010);
DISPLAY 0.659574 (2085 3010);
PAINT MONO (2085 3010);
DISPLAY INVISIBLE (2085 3010);
FORCEPROP 2 LAST CDS_LIB pure_quanta_power
J 0
(2075 2950);
DISPLAY INVISIBLE (2075 2950);
FORCEPROP 1 LAST HDL_POWER GND
J 1
(2100 2875);
DISPLAY 0.872340 (2100 2875);
PAINT GREEN (2100 2875);
DISPLAY INVISIBLE (2100 2875);
FORCEPROP 1 LAST PATH I21
J 0
(2150 2950);
DISPLAY 0.872340 (2150 2950);
PAINT AQUA (2150 2950);
DISPLAY INVISIBLE (2150 2950);
FORCEADD Q_CAP..1
(2075 3225);
FORCEPROP 1 LAST LOCATION PC139_C1P1_6
J 0
(2125 3325);
DISPLAY 0.489362 (2125 3325);
PAINT SKYBLUE (2125 3325);
FORCEPROP 0 LAST $SEC 1
J 0
(2125 3375);
DISPLAY 0.680851 (2125 3375);
PAINT MONO (2125 3375);
DISPLAY INVISIBLE (2125 3375);
FORCEPROP 0 LAST CDS_SEC 1
J 0
(2125 3375);
DISPLAY 1.021277 (2125 3375);
DISPLAY INVISIBLE (2125 3375);
FORCEPROP 1 LASTPIN (2075 3325) $PN 1
J 0
(2085 3305);
DISPLAY 0.489362 (2085 3305);
PAINT MONO (2085 3305);
FORCEPROP 1 LASTPIN (2075 3125) $PN 2
J 0
(2085 3105);
DISPLAY 0.489362 (2085 3105);
PAINT MONO (2085 3105);
FORCEPROP 1 LAST MATERIAL X6S
J 0
(2125 3125);
DISPLAY 0.489362 (2125 3125);
PAINT SKYBLUE (2125 3125);
FORCEPROP 1 LAST TOLERANCE 10%
J 0
(2125 3175);
DISPLAY 0.489362 (2125 3175);
PAINT SKYBLUE (2125 3175);
FORCEPROP 1 LAST VALUE 2.2UF
J 0
(2125 3275);
DISPLAY 0.489362 (2125 3275);
PAINT SKYBLUE (2125 3275);
FORCEPROP 1 LAST VOLTAGE 10V
J 0
(2125 3225);
DISPLAY 0.489362 (2125 3225);
PAINT SKYBLUE (2125 3225);
FORCEPROP 1 LAST PACK_TYPE C0402
J 0
(2125 3025);
DISPLAY 0.489362 (2125 3025);
PAINT SKYBLUE (2125 3025);
FORCEPROP 2 LAST CDS_LIB pure_quanta
J 0
(2075 3225);
DISPLAY INVISIBLE (2075 3225);
FORCEPROP 1 LAST PATH I22
J 0
(2125 3375);
DISPLAY 0.978723 (2125 3375);
PAINT WHITE (2125 3375);
DISPLAY INVISIBLE (2125 3375);
FORCEPROP 1 LAST PART_NUMBER CH5222KEB01
J 0
(2125 3075);
DISPLAY 0.489362 (2125 3075);
PAINT SKYBLUE (2125 3075);
DISPLAY INVISIBLE (2125 3075);
FORCEADD UNIVERSAL_GND..1
(3800 4125);
FORCEPROP 3 LASTPIN (3800 4175) SIG_NAME GND\g
J 0
(3810 4185);
DISPLAY 0.659574 (3810 4185);
PAINT MONO (3810 4185);
DISPLAY INVISIBLE (3810 4185);
FORCEPROP 2 LAST CDS_LIB pure_quanta_power
J 0
(3800 4125);
PAINT MONO (3800 4125);
DISPLAY INVISIBLE (3800 4125);
FORCEPROP 1 LAST HDL_POWER GND
J 1
(3825 4050);
DISPLAY 0.872340 (3825 4050);
PAINT GREEN (3825 4050);
DISPLAY INVISIBLE (3825 4050);
FORCEPROP 1 LAST PATH I23
J 0
(3875 4125);
DISPLAY 0.872340 (3875 4125);
PAINT AQUA (3875 4125);
DISPLAY INVISIBLE (3875 4125);
FORCEADD OFFPAGE..1
(1700 4750);
FORCEPROP 2 LAST $XR5 223 
J 0
(818 4750);
DISPLAY 0.638298 (818 4750);
PAINT MONO (818 4750);
FORCEPROP 2 LAST $XR4 222 
J 0
(938 4750);
DISPLAY 0.638298 (938 4750);
PAINT MONO (938 4750);
FORCEPROP 2 LAST $XR3 220 
J 0
(1058 4750);
DISPLAY 0.638298 (1058 4750);
PAINT MONO (1058 4750);
FORCEPROP 2 LAST $XR2 219 
J 0
(1178 4750);
DISPLAY 0.638298 (1178 4750);
PAINT MONO (1178 4750);
FORCEPROP 2 LAST $XR1 218 
J 0
(1298 4750);
DISPLAY 0.638298 (1298 4750);
PAINT MONO (1298 4750);
FORCEPROP 2 LAST $XR0 217 
J 0
(1418 4750);
DISPLAY 0.638298 (1418 4750);
PAINT MONO (1418 4750);
FORCEPROP 2 LAST CDS_LIB standard
J 0
(1700 4750);
DISPLAY INVISIBLE (1700 4750);
FORCEPROP 1 LAST OFFPAGE TRUE
J 0
(2025 4625);
DISPLAY 0.872340 (2025 4625);
PAINT GREEN (2025 4625);
DISPLAY INVISIBLE (2025 4625);
FORCEPROP 1 LAST COMMENT_BODY TRUE
J 0
(1825 4650);
DISPLAY 0.872340 (1825 4650);
PAINT GREEN (1825 4650);
DISPLAY INVISIBLE (1825 4650);
FORCEPROP 2 LAST PATH I24
J 0
(1450 4800);
DISPLAY 0.680851 (1450 4800);
DISPLAY INVISIBLE (1450 4800);
FORCEADD OFFPAGE..5
(1700 4850);
FORCEPROP 2 LAST $XR0 217 
J 0
(1445 4850);
DISPLAY 0.638298 (1445 4850);
PAINT MONO (1445 4850);
FORCEPROP 2 LAST CDS_LIB standard
J 0
(1700 4850);
DISPLAY INVISIBLE (1700 4850);
FORCEPROP 1 LAST OFFPAGE TRUE
J 0
(2025 4725);
DISPLAY 0.872340 (2025 4725);
PAINT GREEN (2025 4725);
DISPLAY INVISIBLE (2025 4725);
FORCEPROP 1 LAST COMMENT_BODY TRUE
J 0
(1800 4775);
DISPLAY 0.872340 (1800 4775);
PAINT GREEN (1800 4775);
DISPLAY INVISIBLE (1800 4775);
FORCEPROP 2 LAST PATH I25
J 0
(1425 4900);
DISPLAY 0.680851 (1425 4900);
DISPLAY INVISIBLE (1425 4900);
FORCEADD UNIVERSAL_GND..1
(1675 5075);
FORCEPROP 3 LASTPIN (1675 5125) SIG_NAME GND\g
J 0
(1685 5135);
DISPLAY 0.659574 (1685 5135);
PAINT MONO (1685 5135);
DISPLAY INVISIBLE (1685 5135);
FORCEPROP 2 LAST CDS_LIB pure_quanta_power
J 0
(1675 5075);
DISPLAY INVISIBLE (1675 5075);
FORCEPROP 1 LAST HDL_POWER GND
J 1
(1700 5000);
DISPLAY 0.872340 (1700 5000);
PAINT GREEN (1700 5000);
DISPLAY INVISIBLE (1700 5000);
FORCEPROP 1 LAST PATH I26
J 0
(1750 5075);
DISPLAY 0.872340 (1750 5075);
PAINT AQUA (1750 5075);
DISPLAY INVISIBLE (1750 5075);
FORCEADD Q_CAP..1
(1675 5275);
FORCEPROP 1 LAST LOCATION PC421
J 0
(1725 5375);
DISPLAY 0.489362 (1725 5375);
PAINT SKYBLUE (1725 5375);
FORCEPROP 0 LAST $SEC 1
J 0
(1725 5425);
DISPLAY 0.680851 (1725 5425);
PAINT MONO (1725 5425);
DISPLAY INVISIBLE (1725 5425);
FORCEPROP 0 LAST CDS_SEC 1
J 0
(1725 5425);
DISPLAY 1.021277 (1725 5425);
DISPLAY INVISIBLE (1725 5425);
FORCEPROP 1 LASTPIN (1675 5375) $PN 1
J 0
(1685 5355);
DISPLAY 0.489362 (1685 5355);
PAINT MONO (1685 5355);
FORCEPROP 1 LASTPIN (1675 5175) $PN 2
J 0
(1685 5155);
DISPLAY 0.489362 (1685 5155);
PAINT MONO (1685 5155);
FORCEPROP 1 LAST MATERIAL X6S
J 0
(1725 5175);
DISPLAY 0.489362 (1725 5175);
PAINT SKYBLUE (1725 5175);
FORCEPROP 1 LAST TOLERANCE 10%
J 0
(1725 5225);
DISPLAY 0.489362 (1725 5225);
PAINT SKYBLUE (1725 5225);
FORCEPROP 1 LAST VALUE 2.2UF
J 0
(1725 5325);
DISPLAY 0.489362 (1725 5325);
PAINT SKYBLUE (1725 5325);
FORCEPROP 1 LAST VOLTAGE 10V
J 0
(1725 5275);
DISPLAY 0.489362 (1725 5275);
PAINT SKYBLUE (1725 5275);
FORCEPROP 1 LAST PACK_TYPE C0402
J 0
(1725 5075);
DISPLAY 0.489362 (1725 5075);
PAINT SKYBLUE (1725 5075);
FORCEPROP 2 LAST CDS_LIB pure_quanta
J 0
(1675 5275);
DISPLAY INVISIBLE (1675 5275);
FORCEPROP 1 LAST PATH I27
J 0
(1725 5425);
DISPLAY 0.978723 (1725 5425);
PAINT WHITE (1725 5425);
DISPLAY INVISIBLE (1725 5425);
FORCEPROP 1 LAST PART_NUMBER CH5222KEB01
J 0
(1725 5125);
DISPLAY 0.489362 (1725 5125);
PAINT SKYBLUE (1725 5125);
DISPLAY INVISIBLE (1725 5125);
FORCEADD Q_RES..2
(1675 5825);
FORCEPROP 1 LAST LOCATION PR271
J 0
(1720 5950);
DISPLAY 0.489362 (1720 5950);
PAINT SKYBLUE (1720 5950);
FORCEPROP 0 LAST $SEC 1
J 0
(1725 6000);
DISPLAY 0.680851 (1725 6000);
PAINT MONO (1725 6000);
DISPLAY INVISIBLE (1725 6000);
FORCEPROP 0 LAST CDS_SEC 1
J 0
(1725 6000);
DISPLAY 1.021277 (1725 6000);
DISPLAY INVISIBLE (1725 6000);
FORCEPROP 1 LASTPIN (1675 5925) $PN 1
J 0
(1680 5887);
DISPLAY 0.489362 (1680 5887);
PAINT MONO (1680 5887);
FORCEPROP 1 LASTPIN (1675 5725) $PN 2
J 0
(1680 5735);
DISPLAY 0.489362 (1680 5735);
PAINT MONO (1680 5735);
FORCEPROP 1 LAST PACK_TYPE 0402LF
J 0
(1725 5650);
DISPLAY 0.489362 (1725 5650);
PAINT SKYBLUE (1725 5650);
FORCEPROP 1 LAST VALUE 2.2
J 0
(1725 5900);
DISPLAY 0.489362 (1725 5900);
PAINT SKYBLUE (1725 5900);
FORCEPROP 1 LAST TOLERANCE 1%
J 0
(1725 5850);
DISPLAY 0.489362 (1725 5850);
PAINT SKYBLUE (1725 5850);
FORCEPROP 1 LAST MATERIAL CHIP
J 0
(1725 5750);
DISPLAY 0.489362 (1725 5750);
PAINT SKYBLUE (1725 5750);
FORCEPROP 1 LAST WATTAGE 1/16W
J 0
(1725 5800);
DISPLAY 0.489362 (1725 5800);
PAINT SKYBLUE (1725 5800);
FORCEPROP 2 LAST CDS_LIB pure_quanta
J 0
(1675 5825);
DISPLAY INVISIBLE (1675 5825);
FORCEPROP 1 LAST PATH I28
J 0
(1725 6000);
DISPLAY 0.978723 (1725 6000);
PAINT WHITE (1725 6000);
DISPLAY INVISIBLE (1725 6000);
FORCEPROP 1 LAST PART_NUMBER CS-2202FB01
J 0
(1725 5700);
DISPLAY 0.489362 (1725 5700);
PAINT SKYBLUE (1725 5700);
DISPLAY INVISIBLE (1725 5700);
FORCEADD VCC_CORE..1
(1675 6225);
FORCEPROP 3 LASTPIN (1675 6175) SIG_NAME PVDDCR_CPU1_P1_PVCC\g
J 0
(1685 6185);
DISPLAY 0.659574 (1685 6185);
PAINT MONO (1685 6185);
DISPLAY INVISIBLE (1685 6185);
FORCEPROP 1 LAST HDL_POWER PVDDCR_CPU1_P1_PVCC
J 1
(1675 6275);
DISPLAY 0.489362 (1675 6275);
PAINT GREEN (1675 6275);
FORCEPROP 2 LAST CDS_LIB pure_quanta_power
J 0
(1675 6225);
DISPLAY INVISIBLE (1675 6225);
FORCEPROP 1 LAST PATH I29
J 0
(1725 6250);
DISPLAY 0.872340 (1725 6250);
PAINT AQUA (1725 6250);
DISPLAY INVISIBLE (1725 6250);
FORCEADD UNIVERSAL_GND..1
(1275 1500);
FORCEPROP 3 LASTPIN (1275 1550) SIG_NAME GND\g
J 0
(1285 1560);
DISPLAY 0.659574 (1285 1560);
PAINT MONO (1285 1560);
DISPLAY INVISIBLE (1285 1560);
FORCEPROP 2 LAST CDS_LIB pure_quanta_power
J 0
(1275 1500);
PAINT MONO (1275 1500);
DISPLAY INVISIBLE (1275 1500);
FORCEPROP 1 LAST HDL_POWER GND
J 1
(1300 1425);
DISPLAY 0.872340 (1300 1425);
PAINT GREEN (1300 1425);
DISPLAY INVISIBLE (1300 1425);
FORCEPROP 1 LAST PATH I3
J 0
(1350 1500);
DISPLAY 0.872340 (1350 1500);
PAINT AQUA (1350 1500);
DISPLAY INVISIBLE (1350 1500);
FORCEADD UNIVERSAL_GND..1
(2025 5575);
FORCEPROP 3 LASTPIN (2025 5625) SIG_NAME GND\g
J 0
(2035 5635);
DISPLAY 0.659574 (2035 5635);
PAINT MONO (2035 5635);
DISPLAY INVISIBLE (2035 5635);
FORCEPROP 2 LAST CDS_LIB pure_quanta_power
J 0
(2025 5575);
DISPLAY INVISIBLE (2025 5575);
FORCEPROP 1 LAST HDL_POWER GND
J 1
(2050 5500);
DISPLAY 0.872340 (2050 5500);
PAINT GREEN (2050 5500);
DISPLAY INVISIBLE (2050 5500);
FORCEPROP 1 LAST PATH I30
J 0
(2100 5575);
DISPLAY 0.872340 (2100 5575);
PAINT AQUA (2100 5575);
DISPLAY INVISIBLE (2100 5575);
FORCEADD Q_CAP..1
(2025 5850);
FORCEPROP 1 LAST LOCATION PC423_C1P1_5
J 0
(2075 5950);
DISPLAY 0.489362 (2075 5950);
PAINT SKYBLUE (2075 5950);
FORCEPROP 0 LAST $SEC 1
J 0
(2075 6000);
DISPLAY 0.680851 (2075 6000);
PAINT MONO (2075 6000);
DISPLAY INVISIBLE (2075 6000);
FORCEPROP 0 LAST CDS_SEC 1
J 0
(2075 6000);
DISPLAY 1.021277 (2075 6000);
DISPLAY INVISIBLE (2075 6000);
FORCEPROP 1 LASTPIN (2025 5950) $PN 1
J 0
(2035 5930);
DISPLAY 0.489362 (2035 5930);
PAINT MONO (2035 5930);
FORCEPROP 1 LASTPIN (2025 5750) $PN 2
J 0
(2035 5730);
DISPLAY 0.489362 (2035 5730);
PAINT MONO (2035 5730);
FORCEPROP 1 LAST MATERIAL X6S
J 0
(2075 5750);
DISPLAY 0.489362 (2075 5750);
PAINT SKYBLUE (2075 5750);
FORCEPROP 1 LAST TOLERANCE 10%
J 0
(2075 5800);
DISPLAY 0.489362 (2075 5800);
PAINT SKYBLUE (2075 5800);
FORCEPROP 1 LAST VALUE 2.2UF
J 0
(2075 5900);
DISPLAY 0.489362 (2075 5900);
PAINT SKYBLUE (2075 5900);
FORCEPROP 1 LAST VOLTAGE 10V
J 0
(2075 5850);
DISPLAY 0.489362 (2075 5850);
PAINT SKYBLUE (2075 5850);
FORCEPROP 1 LAST PACK_TYPE C0402
J 0
(2075 5650);
DISPLAY 0.489362 (2075 5650);
PAINT SKYBLUE (2075 5650);
FORCEPROP 2 LAST CDS_LIB pure_quanta
J 0
(2025 5850);
DISPLAY INVISIBLE (2025 5850);
FORCEPROP 1 LAST PATH I31
J 0
(2075 6000);
DISPLAY 0.978723 (2075 6000);
PAINT WHITE (2075 6000);
DISPLAY INVISIBLE (2075 6000);
FORCEPROP 1 LAST PART_NUMBER CH5222KEB01
J 0
(2075 5700);
DISPLAY 0.489362 (2075 5700);
PAINT SKYBLUE (2075 5700);
DISPLAY INVISIBLE (2075 5700);
FORCEADD UNIVERSAL_GND..1
(4725 1275);
FORCEPROP 3 LASTPIN (4725 1325) SIG_NAME GND\g
J 0
(4735 1335);
DISPLAY 0.659574 (4735 1335);
PAINT MONO (4735 1335);
DISPLAY INVISIBLE (4735 1335);
FORCEPROP 2 LAST CDS_LIB pure_quanta_power
J 0
(4725 1275);
DISPLAY INVISIBLE (4725 1275);
FORCEPROP 1 LAST HDL_POWER GND
J 1
(4750 1200);
DISPLAY 0.872340 (4750 1200);
PAINT GREEN (4750 1200);
DISPLAY INVISIBLE (4750 1200);
FORCEPROP 1 LAST PATH I32
J 0
(4800 1275);
DISPLAY 0.872340 (4800 1275);
PAINT AQUA (4800 1275);
DISPLAY INVISIBLE (4800 1275);
FORCEADD Q_RES..2
(4725 1500);
FORCEPROP 1 LAST LOCATION PR518
J 0
(4770 1625);
DISPLAY 0.489362 (4770 1625);
PAINT SKYBLUE (4770 1625);
FORCEPROP 0 LAST $SEC 1
J 0
(4775 1675);
DISPLAY 0.680851 (4775 1675);
PAINT MONO (4775 1675);
DISPLAY INVISIBLE (4775 1675);
FORCEPROP 0 LAST CDS_SEC 1
J 0
(4775 1675);
DISPLAY 1.021277 (4775 1675);
DISPLAY INVISIBLE (4775 1675);
FORCEPROP 1 LASTPIN (4725 1600) $PN 1
J 0
(4730 1562);
DISPLAY 0.489362 (4730 1562);
PAINT MONO (4730 1562);
FORCEPROP 1 LASTPIN (4725 1400) $PN 2
J 0
(4730 1410);
DISPLAY 0.489362 (4730 1410);
PAINT MONO (4730 1410);
FORCEPROP 1 LAST PACK_TYPE 0402LF
J 0
(4765 1325);
DISPLAY 0.489362 (4765 1325);
PAINT SKYBLUE (4765 1325);
FORCEPROP 1 LAST MATERIAL EMPTY
J 0
(4765 1425);
DISPLAY 0.489362 (4765 1425);
PAINT RED (4765 1425);
FORCEPROP 1 LAST WATTAGE 1/8W
J 0
(4765 1475);
DISPLAY 0.489362 (4765 1475);
PAINT SKYBLUE (4765 1475);
FORCEPROP 1 LAST TOLERANCE 1%
J 0
(4770 1525);
DISPLAY 0.489362 (4770 1525);
PAINT SKYBLUE (4770 1525);
FORCEPROP 1 LAST VALUE 1.5
J 0
(4770 1575);
DISPLAY 0.489362 (4770 1575);
PAINT SKYBLUE (4770 1575);
FORCEPROP 2 LAST CDS_LIB pure_quanta
J 0
(4725 1500);
DISPLAY INVISIBLE (4725 1500);
FORCEPROP 1 LAST PATH I33
J 0
(4775 1675);
DISPLAY 0.978723 (4775 1675);
PAINT WHITE (4775 1675);
DISPLAY INVISIBLE (4775 1675);
FORCEPROP 1 LAST PART_NUMBER CS-1504FB00
J 0
(4765 1375);
DISPLAY 0.489362 (4765 1375);
PAINT SKYBLUE (4765 1375);
DISPLAY INVISIBLE (4765 1375);
FORCEADD Q_CAP..1
(4725 2025);
FORCEPROP 1 LAST LOCATION PC208
J 0
(4775 2125);
DISPLAY 0.489362 (4775 2125);
PAINT SKYBLUE (4775 2125);
FORCEPROP 0 LAST $SEC 1
J 0
(4775 2175);
DISPLAY 0.680851 (4775 2175);
PAINT MONO (4775 2175);
DISPLAY INVISIBLE (4775 2175);
FORCEPROP 0 LAST CDS_SEC 1
J 0
(4775 2175);
DISPLAY 1.021277 (4775 2175);
DISPLAY INVISIBLE (4775 2175);
FORCEPROP 1 LASTPIN (4725 2125) $PN 1
J 0
(4735 2105);
DISPLAY 0.489362 (4735 2105);
PAINT MONO (4735 2105);
FORCEPROP 1 LASTPIN (4725 1925) $PN 2
J 0
(4735 1905);
DISPLAY 0.489362 (4735 1905);
PAINT MONO (4735 1905);
FORCEPROP 1 LAST PACK_TYPE C0402
J 0
(4775 1825);
DISPLAY 0.489362 (4775 1825);
PAINT SKYBLUE (4775 1825);
FORCEPROP 1 LAST VOLTAGE 50V
J 0
(4775 2025);
DISPLAY 0.489362 (4775 2025);
PAINT SKYBLUE (4775 2025);
FORCEPROP 1 LAST TOLERANCE 10%
J 0
(4775 1975);
DISPLAY 0.489362 (4775 1975);
PAINT SKYBLUE (4775 1975);
FORCEPROP 1 LAST MATERIAL EMPTY
J 0
(4775 1925);
DISPLAY 0.489362 (4775 1925);
PAINT RED (4775 1925);
FORCEPROP 1 LAST VALUE 560PF
J 0
(4775 2075);
DISPLAY 0.489362 (4775 2075);
PAINT SKYBLUE (4775 2075);
FORCEPROP 2 LAST CDS_LIB pure_quanta
J 0
(4725 2025);
DISPLAY INVISIBLE (4725 2025);
FORCEPROP 1 LAST PATH I34
J 0
(4775 2175);
DISPLAY 0.978723 (4775 2175);
PAINT WHITE (4775 2175);
DISPLAY INVISIBLE (4775 2175);
FORCEPROP 1 LAST PART_NUMBER CH1566K1B09
J 0
(4775 1875);
DISPLAY 0.489362 (4775 1875);
PAINT SKYBLUE (4775 1875);
DISPLAY INVISIBLE (4775 1875);
FORCEADD Q_RES..1
(5750 1075);
FORCEPROP 1 LAST LOCATION PR429
J 0
(5700 1100);
DISPLAY 0.489362 (5700 1100);
PAINT SKYBLUE (5700 1100);
FORCEPROP 0 LAST $SEC 1
J 0
(6000 1225);
DISPLAY 0.680851 (6000 1225);
PAINT MONO (6000 1225);
DISPLAY INVISIBLE (6000 1225);
FORCEPROP 0 LAST CDS_SEC 1
J 0
(6000 1225);
DISPLAY 1.021277 (6000 1225);
DISPLAY INVISIBLE (6000 1225);
FORCEPROP 1 LASTPIN (5650 1075) $PN 1
J 0
(5662 1087);
DISPLAY 0.489362 (5662 1087);
PAINT MONO (5662 1087);
FORCEPROP 1 LASTPIN (5850 1075) $PN 2
J 0
(5812 1087);
DISPLAY 0.489362 (5812 1087);
PAINT MONO (5812 1087);
FORCEPROP 1 LAST VALUE 0
J 2
(5550 1100);
DISPLAY 0.489362 (5550 1100);
PAINT SKYBLUE (5550 1100);
FORCEPROP 1 LAST PACK_TYPE 0402LF
J 0
(5875 1025);
DISPLAY 0.489362 (5875 1025);
PAINT SKYBLUE (5875 1025);
FORCEPROP 1 LAST TOLERANCE 5%
J 0
(5550 975);
DISPLAY 0.489362 (5550 975);
PAINT SKYBLUE (5550 975);
FORCEPROP 1 LAST MATERIAL CHIP
J 0
(5900 975);
DISPLAY 0.489362 (5900 975);
PAINT SKYBLUE (5900 975);
FORCEPROP 1 LAST WATTAGE 1/16W
J 2
(6000 1100);
DISPLAY 0.489362 (6000 1100);
PAINT SKYBLUE (6000 1100);
FORCEPROP 2 LAST CDS_LIB pure_quanta
J 0
(5750 1075);
DISPLAY INVISIBLE (5750 1075);
FORCEPROP 1 LAST PATH I35
J 0
(5700 1225);
DISPLAY 0.978723 (5700 1225);
PAINT WHITE (5700 1225);
DISPLAY INVISIBLE (5700 1225);
FORCEPROP 1 LAST PART_NUMBER CS00002JB13
J 0
(5450 1025);
DISPLAY 0.489362 (5450 1025);
PAINT SKYBLUE (5450 1025);
DISPLAY INVISIBLE (5450 1025);
FORCEADD UNIVERSAL_GND..1
(5375 1875);
FORCEPROP 3 LASTPIN (5375 1925) SIG_NAME GND\g
J 0
(5385 1935);
DISPLAY 0.659574 (5385 1935);
PAINT MONO (5385 1935);
DISPLAY INVISIBLE (5385 1935);
FORCEPROP 2 LAST CDS_LIB pure_quanta_power
J 0
(5375 1875);
DISPLAY INVISIBLE (5375 1875);
FORCEPROP 1 LAST HDL_POWER GND
J 1
(5400 1800);
DISPLAY 0.872340 (5400 1800);
PAINT GREEN (5400 1800);
DISPLAY INVISIBLE (5400 1800);
FORCEPROP 1 LAST PATH I36
J 0
(5450 1875);
DISPLAY 0.872340 (5450 1875);
PAINT AQUA (5450 1875);
DISPLAY INVISIBLE (5450 1875);
FORCEADD Q_INDUCTOR..1
R 2
(5575 2000);
FORCEPROP 1 LAST LOCATION PL39
J 0
(5425 2150);
DISPLAY 0.489362 (5425 2150);
PAINT SKYBLUE (5425 2150);
FORCEPROP 0 LAST $SEC 1
J 0
(5425 2175);
DISPLAY 0.680851 (5425 2175);
PAINT MONO (5425 2175);
DISPLAY INVISIBLE (5425 2175);
FORCEPROP 0 LAST CDS_SEC 1
J 0
(5425 2175);
DISPLAY 0.680851 (5425 2175);
DISPLAY INVISIBLE (5425 2175);
FORCEPROP 0 LASTPIN (5675 1975) $PN 1
J 0
(5685 1985);
DISPLAY 0.489362 (5685 1985);
PAINT MONO (5685 1985);
FORCEPROP 0 LASTPIN (5475 1975) $PN 2
J 2
(5465 1985);
DISPLAY 0.489362 (5465 1985);
PAINT MONO (5465 1985);
FORCEPROP 2 LAST PACK_TYPE SMLF
J 0
(5425 2100);
DISPLAY 0.489362 (5425 2100);
PAINT SKYBLUE (5425 2100);
FORCEPROP 1 LAST MATERIAL IND
J 0
(5425 2050);
DISPLAY 0.489362 (5425 2050);
PAINT SKYBLUE (5425 2050);
FORCEPROP 2 LAST VALUE 120NH/69A
J 0
(5425 2125);
DISPLAY 0.489362 (5425 2125);
PAINT SKYBLUE (5425 2125);
FORCEPROP 2 LASTPIN (5675 1975) SIG_NAME IND_CPU1_P1_CPL0
J 0
(5665 1985);
DISPLAY 0.489362 (5665 1985);
FORCEPROP 2 LASTPROP $XRERR UNIQUE?
J 0
(5425 1985);
DISPLAY 0.638298 (5425 1985);
PAINT MONO (5425 1985);
DISPLAY INVISIBLE (5425 1985);
FORCEPROP 1 LAST NEEDS_NO_SIZE TRUE
J 2
(5575 2000);
DISPLAY 0.468085 (5575 2000);
PAINT GREEN (5575 2000);
DISPLAY INVISIBLE (5575 2000);
FORCEPROP 2 LAST CDS_LIB pure_quanta
J 0
(5575 2000);
DISPLAY INVISIBLE (5575 2000);
FORCEPROP 1 LAST PATH I37
J 2
(5500 2055);
DISPLAY 0.723404 (5500 2055);
PAINT GREEN (5500 2055);
DISPLAY INVISIBLE (5500 2055);
FORCEPROP 1 LAST PART_NUMBER CV+12^0EZ03
J 0
(5425 2075);
DISPLAY 0.489362 (5425 2075);
PAINT SKYBLUE (5425 2075);
DISPLAY INVISIBLE (5425 2075);
FORCEADD Q_CAP..1
(4050 3125);
FORCEPROP 1 LAST LOCATION PC141_6
J 0
(4100 3275);
DISPLAY 0.489362 (4100 3275);
PAINT SKYBLUE (4100 3275);
FORCEPROP 0 LAST $SEC 1
J 0
(4100 3275);
DISPLAY 0.680851 (4100 3275);
PAINT MONO (4100 3275);
DISPLAY INVISIBLE (4100 3275);
FORCEPROP 0 LAST CDS_SEC 1
J 0
(4100 3275);
DISPLAY 1.021277 (4100 3275);
DISPLAY INVISIBLE (4100 3275);
FORCEPROP 1 LASTPIN (4050 3225) $PN 1
J 0
(4060 3205);
DISPLAY 0.489362 (4060 3205);
PAINT MONO (4060 3205);
FORCEPROP 1 LASTPIN (4050 3025) $PN 2
J 0
(4060 3005);
DISPLAY 0.489362 (4060 3005);
PAINT MONO (4060 3005);
FORCEPROP 1 LAST VOLTAGE 25V
J 0
(4100 3175);
DISPLAY 0.489362 (4100 3175);
PAINT SKYBLUE (4100 3175);
FORCEPROP 1 LAST TOLERANCE 10%
J 0
(4100 3125);
DISPLAY 0.489362 (4100 3125);
PAINT SKYBLUE (4100 3125);
FORCEPROP 1 LAST VALUE 0.1UF
J 0
(4100 3225);
DISPLAY 0.489362 (4100 3225);
PAINT SKYBLUE (4100 3225);
FORCEPROP 1 LAST MATERIAL X7R
J 0
(4100 3075);
DISPLAY 0.489362 (4100 3075);
PAINT SKYBLUE (4100 3075);
FORCEPROP 1 LAST PACK_TYPE 0402
J 0
(4100 2975);
DISPLAY 0.489362 (4100 2975);
PAINT SKYBLUE (4100 2975);
FORCEPROP 2 LAST CDS_LIB pure_quanta
J 0
(4050 3125);
DISPLAY INVISIBLE (4050 3125);
FORCEPROP 1 LAST PATH I38
J 0
(4100 3275);
DISPLAY 0.978723 (4100 3275);
PAINT WHITE (4100 3275);
DISPLAY INVISIBLE (4100 3275);
FORCEPROP 1 LAST PART_NUMBER CH4104K1B00
J 0
(4100 3025);
DISPLAY 0.489362 (4100 3025);
PAINT SKYBLUE (4100 3025);
DISPLAY INVISIBLE (4100 3025);
FORCEADD Q_RES..1
(4550 2575);
FORCEPROP 1 LAST LOCATION PR428
J 0
(4500 2625);
DISPLAY 0.489362 (4500 2625);
PAINT SKYBLUE (4500 2625);
FORCEPROP 0 LAST $SEC 1
J 0
(4825 2675);
DISPLAY 0.680851 (4825 2675);
PAINT MONO (4825 2675);
DISPLAY INVISIBLE (4825 2675);
FORCEPROP 0 LAST CDS_SEC 1
J 0
(4825 2675);
DISPLAY 1.021277 (4825 2675);
DISPLAY INVISIBLE (4825 2675);
FORCEPROP 1 LASTPIN (4450 2575) $PN 1
J 0
(4462 2587);
DISPLAY 0.787234 (4462 2587);
PAINT MONO (4462 2587);
DISPLAY INVISIBLE (4462 2587);
FORCEPROP 1 LASTPIN (4650 2575) $PN 2
J 0
(4612 2587);
DISPLAY 0.787234 (4612 2587);
PAINT MONO (4612 2587);
DISPLAY INVISIBLE (4612 2587);
FORCEPROP 1 LAST TOLERANCE 1%
J 0
(4400 2475);
DISPLAY 0.489362 (4400 2475);
PAINT SKYBLUE (4400 2475);
FORCEPROP 1 LAST WATTAGE 1/16W
J 2
(4750 2600);
DISPLAY 0.489362 (4750 2600);
PAINT SKYBLUE (4750 2600);
FORCEPROP 1 LAST PACK_TYPE 0402LF
J 0
(4625 2475);
DISPLAY 0.489362 (4625 2475);
PAINT SKYBLUE (4625 2475);
FORCEPROP 1 LAST MATERIAL CHIP
J 0
(4650 2525);
DISPLAY 0.489362 (4650 2525);
PAINT SKYBLUE (4650 2525);
FORCEPROP 1 LAST VALUE 5.6
J 2
(4450 2625);
DISPLAY 0.489362 (4450 2625);
PAINT SKYBLUE (4450 2625);
FORCEPROP 2 LAST CDS_LIB pure_quanta
J 0
(4550 2575);
DISPLAY INVISIBLE (4550 2575);
FORCEPROP 1 LAST PATH I39
J 0
(4500 2725);
DISPLAY 0.978723 (4500 2725);
PAINT WHITE (4500 2725);
DISPLAY INVISIBLE (4500 2725);
FORCEPROP 1 LAST PART_NUMBER CS-5602FB01
J 0
(4250 2525);
DISPLAY 0.489362 (4250 2525);
PAINT SKYBLUE (4250 2525);
DISPLAY INVISIBLE (4250 2525);
FORCEADD Q_RES..2
R 2
(1275 1725);
FORCEPROP 1 LAST LOCATION PR426
J 2
(1230 1850);
DISPLAY 0.489362 (1230 1850);
PAINT SKYBLUE (1230 1850);
FORCEPROP 0 LAST $SEC 1
J 0
(1250 1900);
DISPLAY 0.680851 (1250 1900);
PAINT MONO (1250 1900);
DISPLAY INVISIBLE (1250 1900);
FORCEPROP 0 LAST CDS_SEC 1
J 0
(1250 1900);
DISPLAY 1.021277 (1250 1900);
DISPLAY INVISIBLE (1250 1900);
FORCEPROP 1 LASTPIN (1275 1825) $PN 1
J 2
(1270 1787);
DISPLAY 0.489362 (1270 1787);
PAINT MONO (1270 1787);
FORCEPROP 1 LASTPIN (1275 1625) $PN 2
J 2
(1270 1635);
DISPLAY 0.489362 (1270 1635);
PAINT MONO (1270 1635);
FORCEPROP 1 LAST WATTAGE 1/16W
J 2
(1235 1700);
DISPLAY 0.489362 (1235 1700);
PAINT SKYBLUE (1235 1700);
FORCEPROP 1 LAST MATERIAL EMPTY
J 2
(1235 1650);
DISPLAY 0.489362 (1235 1650);
PAINT RED (1235 1650);
FORCEPROP 1 LAST TOLERANCE 1%
J 2
(1230 1750);
DISPLAY 0.489362 (1230 1750);
PAINT SKYBLUE (1230 1750);
FORCEPROP 1 LAST VALUE 8.87K
J 2
(1230 1800);
DISPLAY 0.489362 (1230 1800);
PAINT SKYBLUE (1230 1800);
FORCEPROP 1 LAST PACK_TYPE 0402LF
J 2
(1235 1550);
DISPLAY 0.489362 (1235 1550);
PAINT SKYBLUE (1235 1550);
FORCEPROP 2 LAST CDS_LIB pure_quanta
J 2
(1275 1725);
DISPLAY INVISIBLE (1275 1725);
FORCEPROP 1 LAST PATH I4
J 2
(1225 1900);
DISPLAY 0.978723 (1225 1900);
PAINT WHITE (1225 1900);
DISPLAY INVISIBLE (1225 1900);
FORCEPROP 1 LAST PART_NUMBER CS28872FB01
J 2
(1235 1600);
DISPLAY 0.489362 (1235 1600);
PAINT SKYBLUE (1235 1600);
DISPLAY INVISIBLE (1235 1600);
FORCEADD Q_CAP..1
(4475 3125);
FORCEPROP 1 LAST LOCATION PC140_6
J 0
(4525 3275);
DISPLAY 0.489362 (4525 3275);
PAINT SKYBLUE (4525 3275);
FORCEPROP 0 LAST $SEC 1
J 0
(4525 3325);
DISPLAY 0.680851 (4525 3325);
PAINT MONO (4525 3325);
DISPLAY INVISIBLE (4525 3325);
FORCEPROP 0 LAST CDS_SEC 1
J 0
(4525 3325);
DISPLAY 1.021277 (4525 3325);
DISPLAY INVISIBLE (4525 3325);
FORCEPROP 1 LASTPIN (4475 3225) $PN 1
J 0
(4485 3205);
DISPLAY 0.489362 (4485 3205);
PAINT MONO (4485 3205);
FORCEPROP 1 LASTPIN (4475 3025) $PN 2
J 0
(4485 3005);
DISPLAY 0.489362 (4485 3005);
PAINT MONO (4485 3005);
FORCEPROP 1 LAST VALUE 1UF
J 0
(4525 3225);
DISPLAY 0.489362 (4525 3225);
PAINT SKYBLUE (4525 3225);
FORCEPROP 1 LAST MATERIAL X6S
J 0
(4525 3075);
DISPLAY 0.489362 (4525 3075);
PAINT SKYBLUE (4525 3075);
FORCEPROP 1 LAST TOLERANCE 10%
J 0
(4525 3125);
DISPLAY 0.489362 (4525 3125);
PAINT SKYBLUE (4525 3125);
FORCEPROP 1 LAST VOLTAGE 25V
J 0
(4525 3175);
DISPLAY 0.489362 (4525 3175);
PAINT SKYBLUE (4525 3175);
FORCEPROP 1 LAST PACK_TYPE C0402
J 0
(4525 3025);
DISPLAY 0.489362 (4525 3025);
PAINT SKYBLUE (4525 3025);
FORCEPROP 2 LAST CDS_LIB pure_quanta
J 0
(4475 3125);
DISPLAY INVISIBLE (4475 3125);
FORCEPROP 1 LAST PATH I40
J 0
(4525 3275);
DISPLAY 0.978723 (4525 3275);
PAINT WHITE (4525 3275);
DISPLAY INVISIBLE (4525 3275);
FORCEPROP 1 LAST PART_NUMBER CH5104KEB02
J 0
(4525 2975);
DISPLAY 0.489362 (4525 2975);
PAINT SKYBLUE (4525 2975);
DISPLAY INVISIBLE (4525 2975);
FORCEADD Q_CAP..1
(4875 3125);
FORCEPROP 1 LAST LOCATION PC144_6
J 0
(4925 3275);
DISPLAY 0.489362 (4925 3275);
PAINT SKYBLUE (4925 3275);
FORCEPROP 0 LAST $SEC 1
J 0
(4925 3325);
DISPLAY 0.680851 (4925 3325);
PAINT MONO (4925 3325);
DISPLAY INVISIBLE (4925 3325);
FORCEPROP 0 LAST CDS_SEC 1
J 0
(4925 3325);
DISPLAY 1.021277 (4925 3325);
DISPLAY INVISIBLE (4925 3325);
FORCEPROP 1 LASTPIN (4875 3225) $PN 1
J 0
(4885 3205);
DISPLAY 0.489362 (4885 3205);
PAINT MONO (4885 3205);
FORCEPROP 1 LASTPIN (4875 3025) $PN 2
J 0
(4885 3005);
DISPLAY 0.489362 (4885 3005);
PAINT MONO (4885 3005);
FORCEPROP 1 LAST PACK_TYPE C0805
J 0
(4925 3025);
DISPLAY 0.489362 (4925 3025);
PAINT SKYBLUE (4925 3025);
FORCEPROP 1 LAST MATERIAL X6S
J 0
(4925 3075);
DISPLAY 0.489362 (4925 3075);
PAINT SKYBLUE (4925 3075);
FORCEPROP 1 LAST VALUE 22UF
J 0
(4925 3225);
DISPLAY 0.489362 (4925 3225);
PAINT SKYBLUE (4925 3225);
FORCEPROP 1 LAST VOLTAGE 16V
J 0
(4925 3175);
DISPLAY 0.489362 (4925 3175);
PAINT SKYBLUE (4925 3175);
FORCEPROP 1 LAST TOLERANCE 20%
J 0
(4925 3125);
DISPLAY 0.489362 (4925 3125);
PAINT SKYBLUE (4925 3125);
FORCEPROP 2 LAST CDS_LIB pure_quanta
J 0
(4875 3125);
DISPLAY INVISIBLE (4875 3125);
FORCEPROP 1 LAST PATH I41
J 0
(4925 3275);
DISPLAY 0.978723 (4925 3275);
PAINT WHITE (4925 3275);
DISPLAY INVISIBLE (4925 3275);
FORCEPROP 1 LAST PART_NUMBER CH6223MEA01
J 0
(4925 2975);
DISPLAY 0.489362 (4925 2975);
PAINT SKYBLUE (4925 2975);
DISPLAY INVISIBLE (4925 2975);
FORCEADD UNIVERSAL_GND..1
(4650 3950);
FORCEPROP 3 LASTPIN (4650 4000) SIG_NAME GND\g
J 0
(4660 4010);
DISPLAY 0.659574 (4660 4010);
PAINT MONO (4660 4010);
DISPLAY INVISIBLE (4660 4010);
FORCEPROP 2 LAST CDS_LIB pure_quanta_power
J 0
(4650 3950);
DISPLAY INVISIBLE (4650 3950);
FORCEPROP 1 LAST HDL_POWER GND
J 1
(4675 3875);
DISPLAY 0.872340 (4675 3875);
PAINT GREEN (4675 3875);
DISPLAY INVISIBLE (4675 3875);
FORCEPROP 1 LAST PATH I42
J 0
(4725 3950);
DISPLAY 0.872340 (4725 3950);
PAINT AQUA (4725 3950);
DISPLAY INVISIBLE (4725 3950);
FORCEADD Q_RES..2
(4650 4175);
FORCEPROP 1 LAST LOCATION PR517
J 0
(4695 4300);
DISPLAY 0.489362 (4695 4300);
PAINT SKYBLUE (4695 4300);
FORCEPROP 0 LAST $SEC 1
J 0
(4700 4350);
DISPLAY 0.680851 (4700 4350);
PAINT MONO (4700 4350);
DISPLAY INVISIBLE (4700 4350);
FORCEPROP 0 LAST CDS_SEC 1
J 0
(4700 4350);
DISPLAY 1.021277 (4700 4350);
DISPLAY INVISIBLE (4700 4350);
FORCEPROP 1 LASTPIN (4650 4275) $PN 1
J 0
(4655 4237);
DISPLAY 0.489362 (4655 4237);
PAINT MONO (4655 4237);
FORCEPROP 1 LASTPIN (4650 4075) $PN 2
J 0
(4655 4085);
DISPLAY 0.489362 (4655 4085);
PAINT MONO (4655 4085);
FORCEPROP 1 LAST WATTAGE 1/8W
J 0
(4690 4150);
DISPLAY 0.489362 (4690 4150);
PAINT SKYBLUE (4690 4150);
FORCEPROP 1 LAST MATERIAL EMPTY
J 0
(4690 4100);
DISPLAY 0.489362 (4690 4100);
PAINT RED (4690 4100);
FORCEPROP 1 LAST TOLERANCE 1%
J 0
(4695 4200);
DISPLAY 0.489362 (4695 4200);
PAINT SKYBLUE (4695 4200);
FORCEPROP 1 LAST VALUE 1.5
J 0
(4695 4250);
DISPLAY 0.489362 (4695 4250);
PAINT SKYBLUE (4695 4250);
FORCEPROP 1 LAST PACK_TYPE 0402LF
J 0
(4690 4000);
DISPLAY 0.489362 (4690 4000);
PAINT SKYBLUE (4690 4000);
FORCEPROP 2 LAST CDS_LIB pure_quanta
J 0
(4650 4175);
DISPLAY INVISIBLE (4650 4175);
FORCEPROP 1 LAST PATH I43
J 0
(4700 4350);
DISPLAY 0.978723 (4700 4350);
PAINT WHITE (4700 4350);
DISPLAY INVISIBLE (4700 4350);
FORCEPROP 1 LAST PART_NUMBER CS-1504FB00
J 0
(4690 4050);
DISPLAY 0.489362 (4690 4050);
PAINT SKYBLUE (4690 4050);
DISPLAY INVISIBLE (4690 4050);
FORCEADD Q_CAP..1
(5275 3125);
FORCEPROP 1 LAST LOCATION PC145_6
J 0
(5325 3275);
DISPLAY 0.489362 (5325 3275);
PAINT SKYBLUE (5325 3275);
FORCEPROP 0 LAST $SEC 1
J 0
(5325 3325);
DISPLAY 0.680851 (5325 3325);
PAINT MONO (5325 3325);
DISPLAY INVISIBLE (5325 3325);
FORCEPROP 0 LAST CDS_SEC 1
J 0
(5325 3325);
DISPLAY 1.021277 (5325 3325);
DISPLAY INVISIBLE (5325 3325);
FORCEPROP 1 LASTPIN (5275 3225) $PN 1
J 0
(5285 3205);
DISPLAY 0.489362 (5285 3205);
PAINT MONO (5285 3205);
FORCEPROP 1 LASTPIN (5275 3025) $PN 2
J 0
(5285 3005);
DISPLAY 0.489362 (5285 3005);
PAINT MONO (5285 3005);
FORCEPROP 1 LAST PACK_TYPE C0805
J 0
(5325 3025);
DISPLAY 0.489362 (5325 3025);
PAINT SKYBLUE (5325 3025);
FORCEPROP 1 LAST MATERIAL X6S
J 0
(5325 3075);
DISPLAY 0.489362 (5325 3075);
PAINT SKYBLUE (5325 3075);
FORCEPROP 1 LAST VALUE 22UF
J 0
(5325 3225);
DISPLAY 0.489362 (5325 3225);
PAINT SKYBLUE (5325 3225);
FORCEPROP 1 LAST VOLTAGE 16V
J 0
(5325 3175);
DISPLAY 0.489362 (5325 3175);
PAINT SKYBLUE (5325 3175);
FORCEPROP 1 LAST TOLERANCE 20%
J 0
(5325 3125);
DISPLAY 0.489362 (5325 3125);
PAINT SKYBLUE (5325 3125);
FORCEPROP 2 LAST CDS_LIB pure_quanta
J 0
(5275 3125);
DISPLAY INVISIBLE (5275 3125);
FORCEPROP 1 LAST PATH I44
J 0
(5325 3275);
DISPLAY 0.978723 (5325 3275);
PAINT WHITE (5325 3275);
DISPLAY INVISIBLE (5325 3275);
FORCEPROP 1 LAST PART_NUMBER CH6223MEA01
J 0
(5325 2975);
DISPLAY 0.489362 (5325 2975);
PAINT SKYBLUE (5325 2975);
DISPLAY INVISIBLE (5325 2975);
FORCEADD Q_CAP..1
(5450 2450);
FORCEPROP 1 LAST LOCATION PC146
J 0
(5500 2550);
DISPLAY 0.489362 (5500 2550);
PAINT SKYBLUE (5500 2550);
FORCEPROP 0 LAST $SEC 1
J 0
(5500 2600);
DISPLAY 0.680851 (5500 2600);
PAINT MONO (5500 2600);
DISPLAY INVISIBLE (5500 2600);
FORCEPROP 0 LAST CDS_SEC 1
J 2
(5500 2575);
DISPLAY 1.021277 (5500 2575);
DISPLAY INVISIBLE (5500 2575);
FORCEPROP 1 LASTPIN (5450 2550) $PN 1
J 0
(5460 2530);
DISPLAY 0.489362 (5460 2530);
PAINT MONO (5460 2530);
FORCEPROP 1 LASTPIN (5450 2350) $PN 2
J 0
(5460 2330);
DISPLAY 0.489362 (5460 2330);
PAINT MONO (5460 2330);
FORCEPROP 1 LAST MATERIAL X7R
J 0
(5500 2350);
DISPLAY 0.489362 (5500 2350);
PAINT SKYBLUE (5500 2350);
FORCEPROP 1 LAST TOLERANCE 10%
J 0
(5500 2400);
DISPLAY 0.489362 (5500 2400);
PAINT SKYBLUE (5500 2400);
FORCEPROP 1 LAST VALUE 0.22UF
J 0
(5500 2500);
DISPLAY 0.489362 (5500 2500);
PAINT SKYBLUE (5500 2500);
FORCEPROP 1 LAST VOLTAGE 16V
J 0
(5500 2450);
DISPLAY 0.489362 (5500 2450);
PAINT SKYBLUE (5500 2450);
FORCEPROP 1 LAST PACK_TYPE 0402
J 0
(5500 2250);
DISPLAY 0.489362 (5500 2250);
PAINT SKYBLUE (5500 2250);
FORCEPROP 2 LAST CDS_LIB pure_quanta
J 2
(5450 2450);
DISPLAY INVISIBLE (5450 2450);
FORCEPROP 1 LAST PATH I45
J 0
(5500 2600);
DISPLAY 0.978723 (5500 2600);
PAINT WHITE (5500 2600);
DISPLAY INVISIBLE (5500 2600);
FORCEPROP 1 LAST PART_NUMBER CH4223K1B00
J 0
(5500 2300);
DISPLAY 0.489362 (5500 2300);
PAINT SKYBLUE (5500 2300);
DISPLAY INVISIBLE (5500 2300);
FORCEADD UNIVERSAL_GND..1
(5650 2775);
FORCEPROP 3 LASTPIN (5650 2825) SIG_NAME GND\g
J 0
(5660 2835);
DISPLAY 0.659574 (5660 2835);
PAINT MONO (5660 2835);
DISPLAY INVISIBLE (5660 2835);
FORCEPROP 2 LAST CDS_LIB pure_quanta_power
J 0
(5650 2775);
PAINT MONO (5650 2775);
DISPLAY INVISIBLE (5650 2775);
FORCEPROP 1 LAST HDL_POWER GND
J 1
(5675 2700);
DISPLAY 0.872340 (5675 2700);
PAINT GREEN (5675 2700);
DISPLAY INVISIBLE (5675 2700);
FORCEPROP 1 LAST PATH I46
J 0
(5725 2775);
DISPLAY 0.872340 (5725 2775);
PAINT AQUA (5725 2775);
DISPLAY INVISIBLE (5725 2775);
FORCEADD Q_CAP..1
(5650 3125);
FORCEPROP 1 LAST LOCATION PC147_6
J 0
(5700 3275);
DISPLAY 0.489362 (5700 3275);
PAINT SKYBLUE (5700 3275);
FORCEPROP 0 LAST $SEC 1
J 0
(5700 3325);
DISPLAY 0.680851 (5700 3325);
PAINT MONO (5700 3325);
DISPLAY INVISIBLE (5700 3325);
FORCEPROP 0 LAST CDS_SEC 1
J 0
(5700 3325);
DISPLAY 1.021277 (5700 3325);
DISPLAY INVISIBLE (5700 3325);
FORCEPROP 1 LASTPIN (5650 3225) $PN 1
J 0
(5660 3205);
DISPLAY 0.489362 (5660 3205);
PAINT MONO (5660 3205);
FORCEPROP 1 LASTPIN (5650 3025) $PN 2
J 0
(5660 3005);
DISPLAY 0.489362 (5660 3005);
PAINT MONO (5660 3005);
FORCEPROP 1 LAST PACK_TYPE C0805
J 0
(5700 3025);
DISPLAY 0.489362 (5700 3025);
PAINT SKYBLUE (5700 3025);
FORCEPROP 1 LAST MATERIAL X6S
J 0
(5700 3075);
DISPLAY 0.489362 (5700 3075);
PAINT SKYBLUE (5700 3075);
FORCEPROP 1 LAST VALUE 22UF
J 0
(5700 3225);
DISPLAY 0.489362 (5700 3225);
PAINT SKYBLUE (5700 3225);
FORCEPROP 1 LAST VOLTAGE 16V
J 0
(5700 3175);
DISPLAY 0.489362 (5700 3175);
PAINT SKYBLUE (5700 3175);
FORCEPROP 1 LAST TOLERANCE 20%
J 0
(5700 3125);
DISPLAY 0.489362 (5700 3125);
PAINT SKYBLUE (5700 3125);
FORCEPROP 2 LAST CDS_LIB pure_quanta
J 0
(5650 3125);
DISPLAY INVISIBLE (5650 3125);
FORCEPROP 1 LAST PATH I47
J 0
(5700 3275);
DISPLAY 0.978723 (5700 3275);
PAINT WHITE (5700 3275);
DISPLAY INVISIBLE (5700 3275);
FORCEPROP 1 LAST PART_NUMBER CH6223MEA01
J 0
(5700 2975);
DISPLAY 0.489362 (5700 2975);
PAINT SKYBLUE (5700 2975);
DISPLAY INVISIBLE (5700 2975);
FORCEADD VCC_CORE..1
(5650 3475);
FORCEPROP 3 LASTPIN (5650 3425) SIG_NAME SW_P12V_AUX_PVDDCR_CPU1_P1_FLT\g
J 0
(5660 3435);
DISPLAY 0.659574 (5660 3435);
PAINT MONO (5660 3435);
DISPLAY INVISIBLE (5660 3435);
FORCEPROP 1 LAST HDL_POWER SW_P12V_AUX_PVDDCR_CPU1_P1_FLT
J 1
(5650 3525);
DISPLAY 0.489362 (5650 3525);
PAINT GREEN (5650 3525);
FORCEPROP 2 LAST CDS_LIB pure_quanta_power
J 0
(5650 3475);
DISPLAY INVISIBLE (5650 3475);
FORCEPROP 1 LAST PATH I48
J 0
(5700 3500);
DISPLAY 0.872340 (5700 3500);
PAINT AQUA (5700 3500);
DISPLAY INVISIBLE (5700 3500);
FORCEADD Q_RES..1
(5575 3800);
FORCEPROP 1 LAST LOCATION PR273
J 0
(5525 3825);
DISPLAY 0.489362 (5525 3825);
PAINT SKYBLUE (5525 3825);
FORCEPROP 0 LAST $SEC 1
J 0
(5825 3950);
DISPLAY 0.680851 (5825 3950);
PAINT MONO (5825 3950);
DISPLAY INVISIBLE (5825 3950);
FORCEPROP 0 LAST CDS_SEC 1
J 0
(5825 3950);
DISPLAY 1.021277 (5825 3950);
DISPLAY INVISIBLE (5825 3950);
FORCEPROP 1 LASTPIN (5475 3800) $PN 1
J 0
(5487 3812);
DISPLAY 0.489362 (5487 3812);
PAINT MONO (5487 3812);
FORCEPROP 1 LASTPIN (5675 3800) $PN 2
J 0
(5637 3812);
DISPLAY 0.489362 (5637 3812);
PAINT MONO (5637 3812);
FORCEPROP 1 LAST TOLERANCE 5%
J 0
(5425 3825);
DISPLAY 0.489362 (5425 3825);
PAINT SKYBLUE (5425 3825);
FORCEPROP 1 LAST PACK_TYPE 0402LF
J 0
(5675 3750);
DISPLAY 0.489362 (5675 3750);
PAINT SKYBLUE (5675 3750);
FORCEPROP 1 LAST VALUE 0
J 2
(5400 3825);
DISPLAY 0.489362 (5400 3825);
PAINT SKYBLUE (5400 3825);
FORCEPROP 1 LAST MATERIAL CHIP
J 0
(5700 3825);
DISPLAY 0.489362 (5700 3825);
PAINT SKYBLUE (5700 3825);
FORCEPROP 1 LAST WATTAGE 1/16W
J 2
(5800 3875);
DISPLAY 0.489362 (5800 3875);
PAINT SKYBLUE (5800 3875);
FORCEPROP 2 LAST CDS_LIB pure_quanta
J 0
(5575 3800);
DISPLAY INVISIBLE (5575 3800);
FORCEPROP 1 LAST PATH I49
J 0
(5525 3950);
DISPLAY 0.978723 (5525 3950);
PAINT WHITE (5525 3950);
DISPLAY INVISIBLE (5525 3950);
FORCEPROP 1 LAST PART_NUMBER CS00002JB13
J 0
(5300 3750);
DISPLAY 0.489362 (5300 3750);
PAINT SKYBLUE (5300 3750);
DISPLAY INVISIBLE (5300 3750);
FORCEADD OFFPAGE..5
(1750 1725);
FORCEPROP 2 LAST $XR3 217 
J 0
(1495 1797);
DISPLAY 0.638298 (1495 1797);
PAINT MONO (1495 1797);
FORCEPROP 2 LAST $XR2 220 
J 0
(1495 1761);
DISPLAY 0.638298 (1495 1761);
PAINT MONO (1495 1761);
FORCEPROP 2 LAST $XR1 219 
J 0
(1495 1689);
DISPLAY 0.638298 (1495 1689);
PAINT MONO (1495 1689);
FORCEPROP 2 LAST $XR0 218 
J 0
(1495 1725);
DISPLAY 0.638298 (1495 1725);
PAINT MONO (1495 1725);
FORCEPROP 2 LAST CDS_LIB standard
J 0
(1750 1725);
DISPLAY INVISIBLE (1750 1725);
FORCEPROP 1 LAST OFFPAGE TRUE
J 0
(2075 1600);
DISPLAY 0.872340 (2075 1600);
PAINT GREEN (2075 1600);
DISPLAY INVISIBLE (2075 1600);
FORCEPROP 1 LAST COMMENT_BODY TRUE
J 0
(1850 1650);
DISPLAY 0.872340 (1850 1650);
PAINT GREEN (1850 1650);
DISPLAY INVISIBLE (1850 1650);
FORCEPROP 2 LAST PATH I5
J 0
(1500 1850);
DISPLAY 0.680851 (1500 1850);
DISPLAY INVISIBLE (1500 1850);
FORCEADD Q_INDUCTOR4P_14..1
(6650 2100);
FORCEPROP 1 LAST LOCATION PL69
J 0
(6425 2355);
DISPLAY 0.489362 (6425 2355);
PAINT SKYBLUE (6425 2355);
FORCEPROP 0 LAST $SEC 1
J 0
(6425 2400);
DISPLAY 0.680851 (6425 2400);
PAINT MONO (6425 2400);
DISPLAY INVISIBLE (6425 2400);
FORCEPROP 0 LAST CDS_SEC 1
J 0
(6425 2400);
DISPLAY 1.021277 (6425 2400);
DISPLAY INVISIBLE (6425 2400);
FORCEPROP 0 LASTPIN (6250 2225) $PN 1
J 2
(6240 2235);
DISPLAY 0.489362 (6240 2235);
PAINT MONO (6240 2235);
FORCEPROP 0 LASTPIN (6250 1975) $PN 2
J 2
(6240 1985);
DISPLAY 0.489362 (6240 1985);
PAINT MONO (6240 1985);
FORCEPROP 0 LASTPIN (7050 1975) $PN 3
J 0
(7060 1985);
DISPLAY 0.489362 (7060 1985);
PAINT MONO (7060 1985);
FORCEPROP 0 LASTPIN (7050 2225) $PN 4
J 0
(7060 2235);
DISPLAY 0.489362 (7060 2235);
PAINT MONO (7060 2235);
FORCEPROP 1 LAST MATERIAL IND
J 0
(6450 2275);
DISPLAY 0.489362 (6450 2275);
PAINT SKYBLUE (6450 2275);
FORCEPROP 2 LAST VALUE 150NH
J 0
(6550 2275);
DISPLAY 0.489362 (6550 2275);
PAINT SKYBLUE (6550 2275);
FORCEPROP 2 LAST PART_TYPE SMLF
J 0
(6575 1850);
DISPLAY 1.021277 (6575 1850);
FORCEPROP 2 LAST CDS_LIB pure_quanta
J 0
(6650 2100);
DISPLAY INVISIBLE (6650 2100);
FORCEPROP 1 LAST NEEDS_NO_SIZE TRUE
J 0
(6650 2100);
DISPLAY 0.468085 (6650 2100);
PAINT GREEN (6650 2100);
DISPLAY INVISIBLE (6650 2100);
FORCEPROP 1 LAST PATH I50
J 0
(6850 2255);
DISPLAY 0.723404 (6850 2255);
PAINT GREEN (6850 2255);
DISPLAY INVISIBLE (6850 2255);
FORCEPROP 1 LAST PART_NUMBER CV+15^0TZ04
J 0
(6700 2275);
DISPLAY 0.489362 (6700 2275);
PAINT SKYBLUE (6700 2275);
DISPLAY INVISIBLE (6700 2275);
FORCEADD OFFPAGE..3
(7675 1975);
FORCEPROP 2 LAST $XR0 220 
J 0
(7979 1975);
DISPLAY 0.638298 (7979 1975);
PAINT MONO (7979 1975);
FORCEPROP 2 LAST CDS_LIB standard
J 0
(7675 1975);
DISPLAY INVISIBLE (7675 1975);
FORCEPROP 1 LAST OFFPAGE TRUE
J 0
(8000 1850);
DISPLAY 0.872340 (8000 1850);
PAINT GREEN (8000 1850);
DISPLAY INVISIBLE (8000 1850);
FORCEPROP 1 LAST COMMENT_BODY TRUE
J 0
(7625 1875);
DISPLAY 0.872340 (7625 1875);
PAINT GREEN (7625 1875);
DISPLAY INVISIBLE (7625 1875);
FORCEPROP 2 LAST PATH I51
J 0
(8000 2025);
DISPLAY 0.680851 (8000 2025);
DISPLAY INVISIBLE (8000 2025);
FORCEADD Q_RES..1
(4500 5200);
FORCEPROP 1 LAST LOCATION PR272
J 0
(4450 5250);
DISPLAY 0.489362 (4450 5250);
PAINT SKYBLUE (4450 5250);
FORCEPROP 0 LAST $SEC 1
J 0
(4775 5300);
DISPLAY 0.680851 (4775 5300);
PAINT MONO (4775 5300);
DISPLAY INVISIBLE (4775 5300);
FORCEPROP 0 LAST CDS_SEC 1
J 0
(4775 5300);
DISPLAY 1.021277 (4775 5300);
DISPLAY INVISIBLE (4775 5300);
FORCEPROP 1 LASTPIN (4400 5200) $PN 1
J 0
(4412 5212);
DISPLAY 0.787234 (4412 5212);
PAINT MONO (4412 5212);
DISPLAY INVISIBLE (4412 5212);
FORCEPROP 1 LASTPIN (4600 5200) $PN 2
J 0
(4562 5212);
DISPLAY 0.787234 (4562 5212);
PAINT MONO (4562 5212);
DISPLAY INVISIBLE (4562 5212);
FORCEPROP 1 LAST WATTAGE 1/16W
J 2
(4700 5225);
DISPLAY 0.489362 (4700 5225);
PAINT SKYBLUE (4700 5225);
FORCEPROP 1 LAST TOLERANCE 1%
J 0
(4325 5100);
DISPLAY 0.489362 (4325 5100);
PAINT SKYBLUE (4325 5100);
FORCEPROP 1 LAST MATERIAL CHIP
J 0
(4575 5150);
DISPLAY 0.489362 (4575 5150);
PAINT SKYBLUE (4575 5150);
FORCEPROP 1 LAST PACK_TYPE 0402LF
J 0
(4550 5100);
DISPLAY 0.489362 (4550 5100);
PAINT SKYBLUE (4550 5100);
FORCEPROP 1 LAST VALUE 5.6
J 2
(4375 5225);
DISPLAY 0.489362 (4375 5225);
PAINT SKYBLUE (4375 5225);
FORCEPROP 2 LAST CDS_LIB pure_quanta
J 0
(4500 5200);
DISPLAY INVISIBLE (4500 5200);
FORCEPROP 1 LAST PATH I52
J 0
(4450 5350);
DISPLAY 0.978723 (4450 5350);
PAINT WHITE (4450 5350);
DISPLAY INVISIBLE (4450 5350);
FORCEPROP 1 LAST PART_NUMBER CS-5602FB01
J 0
(4200 5150);
DISPLAY 0.489362 (4200 5150);
PAINT SKYBLUE (4200 5150);
DISPLAY INVISIBLE (4200 5150);
FORCEADD Q_CAP..1
(4650 4650);
FORCEPROP 1 LAST LOCATION PC207
J 0
(4700 4750);
DISPLAY 0.489362 (4700 4750);
PAINT SKYBLUE (4700 4750);
FORCEPROP 0 LAST $SEC 1
J 0
(4700 4800);
DISPLAY 0.680851 (4700 4800);
PAINT MONO (4700 4800);
DISPLAY INVISIBLE (4700 4800);
FORCEPROP 0 LAST CDS_SEC 1
J 0
(4700 4800);
DISPLAY 1.021277 (4700 4800);
DISPLAY INVISIBLE (4700 4800);
FORCEPROP 1 LASTPIN (4650 4750) $PN 1
J 0
(4660 4730);
DISPLAY 0.489362 (4660 4730);
PAINT MONO (4660 4730);
FORCEPROP 1 LASTPIN (4650 4550) $PN 2
J 0
(4660 4530);
DISPLAY 0.489362 (4660 4530);
PAINT MONO (4660 4530);
FORCEPROP 1 LAST VALUE 560PF
J 0
(4700 4700);
DISPLAY 0.489362 (4700 4700);
PAINT SKYBLUE (4700 4700);
FORCEPROP 1 LAST VOLTAGE 50V
J 0
(4700 4650);
DISPLAY 0.489362 (4700 4650);
PAINT SKYBLUE (4700 4650);
FORCEPROP 1 LAST MATERIAL EMPTY
J 0
(4700 4550);
DISPLAY 0.489362 (4700 4550);
PAINT RED (4700 4550);
FORCEPROP 1 LAST TOLERANCE 10%
J 0
(4700 4600);
DISPLAY 0.489362 (4700 4600);
PAINT SKYBLUE (4700 4600);
FORCEPROP 1 LAST PACK_TYPE C0402
J 0
(4700 4450);
DISPLAY 0.489362 (4700 4450);
PAINT SKYBLUE (4700 4450);
FORCEPROP 2 LAST CDS_LIB pure_quanta
J 0
(4650 4650);
DISPLAY INVISIBLE (4650 4650);
FORCEPROP 1 LAST PATH I53
J 0
(4700 4800);
DISPLAY 0.978723 (4700 4800);
PAINT WHITE (4700 4800);
DISPLAY INVISIBLE (4700 4800);
FORCEPROP 1 LAST PART_NUMBER CH1566K1B09
J 0
(4700 4500);
DISPLAY 0.489362 (4700 4500);
PAINT SKYBLUE (4700 4500);
DISPLAY INVISIBLE (4700 4500);
FORCEADD Q_CAP..1
(4000 5750);
FORCEPROP 1 LAST LOCATION PC425_5
J 0
(4050 5900);
DISPLAY 0.489362 (4050 5900);
PAINT SKYBLUE (4050 5900);
FORCEPROP 0 LAST $SEC 1
J 0
(4050 5900);
DISPLAY 0.680851 (4050 5900);
PAINT MONO (4050 5900);
DISPLAY INVISIBLE (4050 5900);
FORCEPROP 0 LAST CDS_SEC 1
J 0
(4050 5900);
DISPLAY 1.021277 (4050 5900);
DISPLAY INVISIBLE (4050 5900);
FORCEPROP 1 LASTPIN (4000 5850) $PN 1
J 0
(4010 5830);
DISPLAY 0.489362 (4010 5830);
PAINT MONO (4010 5830);
FORCEPROP 1 LASTPIN (4000 5650) $PN 2
J 0
(4010 5630);
DISPLAY 0.489362 (4010 5630);
PAINT MONO (4010 5630);
FORCEPROP 1 LAST VALUE 0.1UF
J 0
(4050 5850);
DISPLAY 0.489362 (4050 5850);
PAINT SKYBLUE (4050 5850);
FORCEPROP 1 LAST TOLERANCE 10%
J 0
(4050 5750);
DISPLAY 0.489362 (4050 5750);
PAINT SKYBLUE (4050 5750);
FORCEPROP 1 LAST VOLTAGE 25V
J 0
(4050 5800);
DISPLAY 0.489362 (4050 5800);
PAINT SKYBLUE (4050 5800);
FORCEPROP 1 LAST MATERIAL X7R
J 0
(4050 5700);
DISPLAY 0.489362 (4050 5700);
PAINT SKYBLUE (4050 5700);
FORCEPROP 1 LAST PACK_TYPE 0402
J 0
(4050 5600);
DISPLAY 0.489362 (4050 5600);
PAINT SKYBLUE (4050 5600);
FORCEPROP 2 LAST CDS_LIB pure_quanta
J 0
(4000 5750);
DISPLAY INVISIBLE (4000 5750);
FORCEPROP 1 LAST PATH I54
J 0
(4050 5900);
DISPLAY 0.978723 (4050 5900);
PAINT WHITE (4050 5900);
DISPLAY INVISIBLE (4050 5900);
FORCEPROP 1 LAST PART_NUMBER CH4104K1B00
J 0
(4050 5650);
DISPLAY 0.489362 (4050 5650);
PAINT SKYBLUE (4050 5650);
DISPLAY INVISIBLE (4050 5650);
FORCEADD Q_CAP..1
(4425 5750);
FORCEPROP 1 LAST LOCATION PC424_5
J 0
(4475 5900);
DISPLAY 0.489362 (4475 5900);
PAINT SKYBLUE (4475 5900);
FORCEPROP 0 LAST $SEC 1
J 0
(4475 5950);
DISPLAY 0.680851 (4475 5950);
PAINT MONO (4475 5950);
DISPLAY INVISIBLE (4475 5950);
FORCEPROP 0 LAST CDS_SEC 1
J 0
(4475 5950);
DISPLAY 1.021277 (4475 5950);
DISPLAY INVISIBLE (4475 5950);
FORCEPROP 1 LASTPIN (4425 5850) $PN 1
J 0
(4435 5830);
DISPLAY 0.489362 (4435 5830);
PAINT MONO (4435 5830);
FORCEPROP 1 LASTPIN (4425 5650) $PN 2
J 0
(4435 5630);
DISPLAY 0.489362 (4435 5630);
PAINT MONO (4435 5630);
FORCEPROP 1 LAST TOLERANCE 10%
J 0
(4475 5750);
DISPLAY 0.489362 (4475 5750);
PAINT SKYBLUE (4475 5750);
FORCEPROP 1 LAST VALUE 1UF
J 0
(4475 5850);
DISPLAY 0.489362 (4475 5850);
PAINT SKYBLUE (4475 5850);
FORCEPROP 1 LAST VOLTAGE 25V
J 0
(4475 5800);
DISPLAY 0.489362 (4475 5800);
PAINT SKYBLUE (4475 5800);
FORCEPROP 1 LAST MATERIAL X6S
J 0
(4475 5700);
DISPLAY 0.489362 (4475 5700);
PAINT SKYBLUE (4475 5700);
FORCEPROP 1 LAST PACK_TYPE C0402
J 0
(4475 5650);
DISPLAY 0.489362 (4475 5650);
PAINT SKYBLUE (4475 5650);
FORCEPROP 2 LAST CDS_LIB pure_quanta
J 0
(4425 5750);
DISPLAY INVISIBLE (4425 5750);
FORCEPROP 1 LAST PATH I55
J 0
(4475 5900);
DISPLAY 0.978723 (4475 5900);
PAINT WHITE (4475 5900);
DISPLAY INVISIBLE (4475 5900);
FORCEPROP 1 LAST PART_NUMBER CH5104KEB02
J 0
(4475 5600);
DISPLAY 0.489362 (4475 5600);
PAINT SKYBLUE (4475 5600);
DISPLAY INVISIBLE (4475 5600);
FORCEADD Q_CAP..1
(4825 5750);
FORCEPROP 1 LAST LOCATION PC426_5
J 0
(4875 5900);
DISPLAY 0.489362 (4875 5900);
PAINT SKYBLUE (4875 5900);
FORCEPROP 0 LAST $SEC 1
J 0
(4875 5950);
DISPLAY 0.680851 (4875 5950);
PAINT MONO (4875 5950);
DISPLAY INVISIBLE (4875 5950);
FORCEPROP 0 LAST CDS_SEC 1
J 0
(4875 5950);
DISPLAY 1.021277 (4875 5950);
DISPLAY INVISIBLE (4875 5950);
FORCEPROP 1 LASTPIN (4825 5850) $PN 1
J 0
(4835 5830);
DISPLAY 0.489362 (4835 5830);
PAINT MONO (4835 5830);
FORCEPROP 1 LASTPIN (4825 5650) $PN 2
J 0
(4835 5630);
DISPLAY 0.489362 (4835 5630);
PAINT MONO (4835 5630);
FORCEPROP 1 LAST PACK_TYPE C0805
J 0
(4875 5650);
DISPLAY 0.489362 (4875 5650);
PAINT SKYBLUE (4875 5650);
FORCEPROP 1 LAST MATERIAL X6S
J 0
(4875 5700);
DISPLAY 0.489362 (4875 5700);
PAINT SKYBLUE (4875 5700);
FORCEPROP 1 LAST VOLTAGE 16V
J 0
(4875 5800);
DISPLAY 0.489362 (4875 5800);
PAINT SKYBLUE (4875 5800);
FORCEPROP 1 LAST TOLERANCE 20%
J 0
(4875 5750);
DISPLAY 0.489362 (4875 5750);
PAINT SKYBLUE (4875 5750);
FORCEPROP 1 LAST VALUE 22UF
J 0
(4875 5850);
DISPLAY 0.489362 (4875 5850);
PAINT SKYBLUE (4875 5850);
FORCEPROP 2 LAST CDS_LIB pure_quanta
J 0
(4825 5750);
DISPLAY INVISIBLE (4825 5750);
FORCEPROP 1 LAST PATH I56
J 0
(4875 5900);
DISPLAY 0.978723 (4875 5900);
PAINT WHITE (4875 5900);
DISPLAY INVISIBLE (4875 5900);
FORCEPROP 1 LAST PART_NUMBER CH6223MEA01
J 0
(4875 5600);
DISPLAY 0.489362 (4875 5600);
PAINT SKYBLUE (4875 5600);
DISPLAY INVISIBLE (4875 5600);
FORCEADD Q_CAP..1
(5400 5075);
FORCEPROP 1 LAST LOCATION PC428
J 0
(5450 5175);
DISPLAY 0.489362 (5450 5175);
PAINT SKYBLUE (5450 5175);
FORCEPROP 0 LAST $SEC 1
J 0
(5450 5225);
DISPLAY 0.680851 (5450 5225);
PAINT MONO (5450 5225);
DISPLAY INVISIBLE (5450 5225);
FORCEPROP 0 LAST CDS_SEC 1
J 2
(5450 5200);
DISPLAY 1.021277 (5450 5200);
DISPLAY INVISIBLE (5450 5200);
FORCEPROP 1 LASTPIN (5400 5175) $PN 1
J 0
(5410 5155);
DISPLAY 0.489362 (5410 5155);
PAINT MONO (5410 5155);
FORCEPROP 1 LASTPIN (5400 4975) $PN 2
J 0
(5410 4955);
DISPLAY 0.489362 (5410 4955);
PAINT MONO (5410 4955);
FORCEPROP 1 LAST VOLTAGE 16V
J 0
(5450 5075);
DISPLAY 0.489362 (5450 5075);
PAINT SKYBLUE (5450 5075);
FORCEPROP 1 LAST PACK_TYPE 0402
J 0
(5450 4875);
DISPLAY 0.489362 (5450 4875);
PAINT SKYBLUE (5450 4875);
FORCEPROP 1 LAST MATERIAL X7R
J 0
(5450 4975);
DISPLAY 0.489362 (5450 4975);
PAINT SKYBLUE (5450 4975);
FORCEPROP 1 LAST TOLERANCE 10%
J 0
(5450 5025);
DISPLAY 0.489362 (5450 5025);
PAINT SKYBLUE (5450 5025);
FORCEPROP 1 LAST VALUE 0.22UF
J 0
(5450 5125);
DISPLAY 0.489362 (5450 5125);
PAINT SKYBLUE (5450 5125);
FORCEPROP 2 LAST CDS_LIB pure_quanta
J 2
(5400 5075);
DISPLAY INVISIBLE (5400 5075);
FORCEPROP 1 LAST PATH I57
J 0
(5450 5225);
DISPLAY 0.978723 (5450 5225);
PAINT WHITE (5450 5225);
DISPLAY INVISIBLE (5450 5225);
FORCEPROP 1 LAST PART_NUMBER CH4223K1B00
J 0
(5450 4925);
DISPLAY 0.489362 (5450 4925);
PAINT SKYBLUE (5450 4925);
DISPLAY INVISIBLE (5450 4925);
FORCEADD OFFPAGE..6
(5650 4600);
FORCEPROP 2 LAST $XR0 220 
J 0
(5370 4600);
DISPLAY 0.638298 (5370 4600);
PAINT MONO (5370 4600);
FORCEPROP 2 LAST CDS_LIB standard
J 0
(5650 4600);
DISPLAY INVISIBLE (5650 4600);
FORCEPROP 1 LAST OFFPAGE TRUE
J 0
(5975 4475);
DISPLAY 0.872340 (5975 4475);
PAINT GREEN (5975 4475);
DISPLAY INVISIBLE (5975 4475);
FORCEPROP 1 LAST COMMENT_BODY TRUE
J 0
(5750 4525);
DISPLAY 0.872340 (5750 4525);
PAINT GREEN (5750 4525);
DISPLAY INVISIBLE (5750 4525);
FORCEPROP 2 LAST PATH I58
J 0
(5350 4650);
DISPLAY 0.680851 (5350 4650);
DISPLAY INVISIBLE (5350 4650);
FORCEADD UNIVERSAL_GND..1
(5600 5400);
FORCEPROP 3 LASTPIN (5600 5450) SIG_NAME GND\g
J 0
(5610 5460);
DISPLAY 0.659574 (5610 5460);
PAINT MONO (5610 5460);
DISPLAY INVISIBLE (5610 5460);
FORCEPROP 2 LAST CDS_LIB pure_quanta_power
J 0
(5600 5400);
PAINT MONO (5600 5400);
DISPLAY INVISIBLE (5600 5400);
FORCEPROP 1 LAST HDL_POWER GND
J 1
(5625 5325);
DISPLAY 0.872340 (5625 5325);
PAINT GREEN (5625 5325);
DISPLAY INVISIBLE (5625 5325);
FORCEPROP 1 LAST PATH I59
J 0
(5675 5400);
DISPLAY 0.872340 (5675 5400);
PAINT AQUA (5675 5400);
DISPLAY INVISIBLE (5675 5400);
FORCEADD OFFPAGE..1
(1750 1625);
FORCEPROP 2 LAST $XR0 217 
J 0
(1498 1625);
DISPLAY 0.638298 (1498 1625);
PAINT MONO (1498 1625);
FORCEPROP 2 LAST CDS_LIB standard
J 0
(1750 1625);
DISPLAY INVISIBLE (1750 1625);
FORCEPROP 1 LAST OFFPAGE TRUE
J 0
(2075 1500);
DISPLAY 0.872340 (2075 1500);
PAINT GREEN (2075 1500);
DISPLAY INVISIBLE (2075 1500);
FORCEPROP 1 LAST COMMENT_BODY TRUE
J 0
(1875 1525);
DISPLAY 0.872340 (1875 1525);
PAINT GREEN (1875 1525);
DISPLAY INVISIBLE (1875 1525);
FORCEPROP 2 LAST PATH I6
J 0
(1500 1675);
DISPLAY 0.680851 (1500 1675);
DISPLAY INVISIBLE (1500 1675);
FORCEADD Q_CAP..1
(5225 5750);
FORCEPROP 1 LAST LOCATION PC427_5
J 0
(5275 5900);
DISPLAY 0.489362 (5275 5900);
PAINT SKYBLUE (5275 5900);
FORCEPROP 0 LAST $SEC 1
J 0
(5275 5950);
DISPLAY 0.680851 (5275 5950);
PAINT MONO (5275 5950);
DISPLAY INVISIBLE (5275 5950);
FORCEPROP 0 LAST CDS_SEC 1
J 0
(5275 5950);
DISPLAY 1.021277 (5275 5950);
DISPLAY INVISIBLE (5275 5950);
FORCEPROP 1 LASTPIN (5225 5850) $PN 1
J 0
(5235 5830);
DISPLAY 0.489362 (5235 5830);
PAINT MONO (5235 5830);
FORCEPROP 1 LASTPIN (5225 5650) $PN 2
J 0
(5235 5630);
DISPLAY 0.489362 (5235 5630);
PAINT MONO (5235 5630);
FORCEPROP 1 LAST VALUE 22UF
J 0
(5275 5850);
DISPLAY 0.489362 (5275 5850);
PAINT SKYBLUE (5275 5850);
FORCEPROP 1 LAST VOLTAGE 16V
J 0
(5275 5800);
DISPLAY 0.489362 (5275 5800);
PAINT SKYBLUE (5275 5800);
FORCEPROP 1 LAST TOLERANCE 20%
J 0
(5275 5750);
DISPLAY 0.489362 (5275 5750);
PAINT SKYBLUE (5275 5750);
FORCEPROP 1 LAST MATERIAL X6S
J 0
(5275 5700);
DISPLAY 0.489362 (5275 5700);
PAINT SKYBLUE (5275 5700);
FORCEPROP 1 LAST PACK_TYPE C0805
J 0
(5275 5650);
DISPLAY 0.489362 (5275 5650);
PAINT SKYBLUE (5275 5650);
FORCEPROP 2 LAST CDS_LIB pure_quanta
J 0
(5225 5750);
DISPLAY INVISIBLE (5225 5750);
FORCEPROP 1 LAST PATH I60
J 0
(5275 5900);
DISPLAY 0.978723 (5275 5900);
PAINT WHITE (5275 5900);
DISPLAY INVISIBLE (5275 5900);
FORCEPROP 1 LAST PART_NUMBER CH6223MEA01
J 0
(5275 5600);
DISPLAY 0.489362 (5275 5600);
PAINT SKYBLUE (5275 5600);
DISPLAY INVISIBLE (5275 5600);
FORCEADD Q_CAP..1
(5600 5750);
FORCEPROP 1 LAST LOCATION PC429_5
J 0
(5650 5900);
DISPLAY 0.489362 (5650 5900);
PAINT SKYBLUE (5650 5900);
FORCEPROP 0 LAST $SEC 1
J 0
(5650 5950);
DISPLAY 0.680851 (5650 5950);
PAINT MONO (5650 5950);
DISPLAY INVISIBLE (5650 5950);
FORCEPROP 0 LAST CDS_SEC 1
J 0
(5650 5950);
DISPLAY 1.021277 (5650 5950);
DISPLAY INVISIBLE (5650 5950);
FORCEPROP 1 LASTPIN (5600 5850) $PN 1
J 0
(5610 5830);
DISPLAY 0.489362 (5610 5830);
PAINT MONO (5610 5830);
FORCEPROP 1 LASTPIN (5600 5650) $PN 2
J 0
(5610 5630);
DISPLAY 0.489362 (5610 5630);
PAINT MONO (5610 5630);
FORCEPROP 1 LAST PACK_TYPE C0805
J 0
(5650 5650);
DISPLAY 0.489362 (5650 5650);
PAINT SKYBLUE (5650 5650);
FORCEPROP 1 LAST MATERIAL X6S
J 0
(5650 5700);
DISPLAY 0.489362 (5650 5700);
PAINT SKYBLUE (5650 5700);
FORCEPROP 1 LAST VALUE 22UF
J 0
(5650 5850);
DISPLAY 0.489362 (5650 5850);
PAINT SKYBLUE (5650 5850);
FORCEPROP 1 LAST VOLTAGE 16V
J 0
(5650 5800);
DISPLAY 0.489362 (5650 5800);
PAINT SKYBLUE (5650 5800);
FORCEPROP 1 LAST TOLERANCE 20%
J 0
(5650 5750);
DISPLAY 0.489362 (5650 5750);
PAINT SKYBLUE (5650 5750);
FORCEPROP 2 LAST CDS_LIB pure_quanta
J 0
(5600 5750);
DISPLAY INVISIBLE (5600 5750);
FORCEPROP 1 LAST PATH I61
J 0
(5650 5900);
DISPLAY 0.978723 (5650 5900);
PAINT WHITE (5650 5900);
DISPLAY INVISIBLE (5650 5900);
FORCEPROP 1 LAST PART_NUMBER CH6223MEA01
J 0
(5650 5600);
DISPLAY 0.489362 (5650 5600);
PAINT SKYBLUE (5650 5600);
DISPLAY INVISIBLE (5650 5600);
FORCEADD VCC_CORE..1
(5600 6100);
FORCEPROP 3 LASTPIN (5600 6050) SIG_NAME SW_P12V_AUX_PVDDCR_CPU1_P1_FLT\g
J 0
(5610 6060);
DISPLAY 0.659574 (5610 6060);
PAINT MONO (5610 6060);
DISPLAY INVISIBLE (5610 6060);
FORCEPROP 1 LAST HDL_POWER SW_P12V_AUX_PVDDCR_CPU1_P1_FLT
J 1
(5600 6150);
DISPLAY 0.489362 (5600 6150);
PAINT GREEN (5600 6150);
FORCEPROP 2 LAST CDS_LIB pure_quanta_power
J 0
(5600 6100);
DISPLAY INVISIBLE (5600 6100);
FORCEPROP 1 LAST PATH I62
J 0
(5650 6125);
DISPLAY 0.872340 (5650 6125);
PAINT AQUA (5650 6125);
DISPLAY INVISIBLE (5650 6125);
FORCEADD Q_INDUCTOR4P_14..1
(6600 4725);
FORCEPROP 1 LAST LOCATION PL45
J 0
(6375 4980);
DISPLAY 0.489362 (6375 4980);
PAINT SKYBLUE (6375 4980);
FORCEPROP 0 LAST $SEC 1
J 0
(6375 5025);
DISPLAY 0.680851 (6375 5025);
PAINT MONO (6375 5025);
DISPLAY INVISIBLE (6375 5025);
FORCEPROP 0 LAST CDS_SEC 1
J 0
(6375 5025);
DISPLAY 1.021277 (6375 5025);
DISPLAY INVISIBLE (6375 5025);
FORCEPROP 0 LASTPIN (6200 4850) $PN 1
J 2
(6190 4860);
DISPLAY 0.489362 (6190 4860);
PAINT MONO (6190 4860);
FORCEPROP 0 LASTPIN (6200 4600) $PN 2
J 2
(6190 4610);
DISPLAY 0.489362 (6190 4610);
PAINT MONO (6190 4610);
FORCEPROP 0 LASTPIN (7000 4600) $PN 3
J 0
(7010 4610);
DISPLAY 0.489362 (7010 4610);
PAINT MONO (7010 4610);
FORCEPROP 0 LASTPIN (7000 4850) $PN 4
J 0
(7010 4860);
DISPLAY 0.489362 (7010 4860);
PAINT MONO (7010 4860);
FORCEPROP 2 LAST PART_TYPE SMLF
J 0
(6525 4475);
DISPLAY 1.021277 (6525 4475);
FORCEPROP 1 LAST MATERIAL IND
J 0
(6400 4900);
DISPLAY 0.489362 (6400 4900);
PAINT SKYBLUE (6400 4900);
FORCEPROP 2 LAST VALUE 150NH
J 0
(6500 4900);
DISPLAY 0.489362 (6500 4900);
PAINT SKYBLUE (6500 4900);
FORCEPROP 1 LAST NEEDS_NO_SIZE TRUE
J 0
(6600 4725);
DISPLAY 0.468085 (6600 4725);
PAINT GREEN (6600 4725);
DISPLAY INVISIBLE (6600 4725);
FORCEPROP 2 LAST CDS_LIB pure_quanta
J 0
(6600 4725);
DISPLAY INVISIBLE (6600 4725);
FORCEPROP 1 LAST PATH I63
J 0
(6800 4880);
DISPLAY 0.723404 (6800 4880);
PAINT GREEN (6800 4880);
DISPLAY INVISIBLE (6800 4880);
FORCEPROP 1 LAST PART_NUMBER CV+15^0TZ04
J 0
(6650 4900);
DISPLAY 0.489362 (6650 4900);
PAINT SKYBLUE (6650 4900);
DISPLAY INVISIBLE (6650 4900);
FORCEADD OFFPAGE..3
(7625 4600);
FORCEPROP 2 LAST $XR0 218 
J 0
(7929 4600);
DISPLAY 0.638298 (7929 4600);
PAINT MONO (7929 4600);
FORCEPROP 2 LAST CDS_LIB standard
J 0
(7625 4600);
DISPLAY INVISIBLE (7625 4600);
FORCEPROP 1 LAST OFFPAGE TRUE
J 0
(7950 4475);
DISPLAY 0.872340 (7950 4475);
PAINT GREEN (7950 4475);
DISPLAY INVISIBLE (7950 4475);
FORCEPROP 1 LAST COMMENT_BODY TRUE
J 0
(7575 4500);
DISPLAY 0.872340 (7575 4500);
PAINT GREEN (7575 4500);
DISPLAY INVISIBLE (7575 4500);
FORCEPROP 2 LAST PATH I64
J 0
(7950 4650);
DISPLAY 0.680851 (7950 4650);
DISPLAY INVISIBLE (7950 4650);
FORCEADD Q_CAP..1
(8150 2025);
FORCEPROP 1 LAST LOCATION PC148_6
J 0
(8200 2150);
DISPLAY 0.489362 (8200 2150);
PAINT SKYBLUE (8200 2150);
FORCEPROP 0 LAST $SEC 1
J 0
(8200 2200);
DISPLAY 0.680851 (8200 2200);
PAINT MONO (8200 2200);
DISPLAY INVISIBLE (8200 2200);
FORCEPROP 0 LAST CDS_SEC 1
J 0
(8200 2200);
DISPLAY 1.021277 (8200 2200);
DISPLAY INVISIBLE (8200 2200);
FORCEPROP 1 LASTPIN (8150 2125) $PN 1
J 0
(8160 2105);
DISPLAY 0.489362 (8160 2105);
PAINT MONO (8160 2105);
FORCEPROP 1 LASTPIN (8150 1925) $PN 2
J 0
(8160 1905);
DISPLAY 0.489362 (8160 1905);
PAINT MONO (8160 1905);
FORCEPROP 1 LAST VOLTAGE 4V
J 0
(8200 2050);
DISPLAY 0.489362 (8200 2050);
PAINT SKYBLUE (8200 2050);
FORCEPROP 1 LAST VALUE 22UF
J 0
(8200 2100);
DISPLAY 0.489362 (8200 2100);
PAINT SKYBLUE (8200 2100);
FORCEPROP 1 LAST TOLERANCE 20%
J 0
(8200 2000);
DISPLAY 0.489362 (8200 2000);
PAINT SKYBLUE (8200 2000);
FORCEPROP 1 LAST MATERIAL X6S
J 0
(8200 1950);
DISPLAY 0.489362 (8200 1950);
PAINT SKYBLUE (8200 1950);
FORCEPROP 1 LAST PACK_TYPE C0805
J 0
(8200 1900);
DISPLAY 0.489362 (8200 1900);
PAINT SKYBLUE (8200 1900);
FORCEPROP 2 LAST CDS_LIB pure_quanta
J 0
(8150 2025);
DISPLAY INVISIBLE (8150 2025);
FORCEPROP 1 LAST PATH I65
J 0
(8200 2175);
DISPLAY 0.978723 (8200 2175);
PAINT WHITE (8200 2175);
DISPLAY INVISIBLE (8200 2175);
FORCEPROP 1 LAST PART_NUMBER CH622KMEA03
J 0
(8200 1850);
DISPLAY 0.489362 (8200 1850);
PAINT SKYBLUE (8200 1850);
DISPLAY INVISIBLE (8200 1850);
FORCEADD UNIVERSAL_GND..1
(8575 1675);
FORCEPROP 3 LASTPIN (8575 1725) SIG_NAME GND\g
J 0
(8585 1735);
DISPLAY 0.659574 (8585 1735);
PAINT MONO (8585 1735);
DISPLAY INVISIBLE (8585 1735);
FORCEPROP 2 LAST CDS_LIB pure_quanta_power
J 0
(8575 1675);
PAINT MONO (8575 1675);
DISPLAY INVISIBLE (8575 1675);
FORCEPROP 1 LAST HDL_POWER GND
J 1
(8600 1600);
DISPLAY 0.872340 (8600 1600);
PAINT GREEN (8600 1600);
DISPLAY INVISIBLE (8600 1600);
FORCEPROP 1 LAST PATH I66
J 0
(8650 1675);
DISPLAY 0.872340 (8650 1675);
PAINT AQUA (8650 1675);
DISPLAY INVISIBLE (8650 1675);
FORCEADD Q_CAP..1
(8575 2025);
FORCEPROP 1 LAST LOCATION PC149_6
J 0
(8625 2150);
DISPLAY 0.489362 (8625 2150);
PAINT SKYBLUE (8625 2150);
FORCEPROP 0 LAST $SEC 1
J 0
(8625 2200);
DISPLAY 0.680851 (8625 2200);
PAINT MONO (8625 2200);
DISPLAY INVISIBLE (8625 2200);
FORCEPROP 0 LAST CDS_SEC 1
J 0
(8625 2200);
DISPLAY 1.021277 (8625 2200);
DISPLAY INVISIBLE (8625 2200);
FORCEPROP 1 LASTPIN (8575 2125) $PN 1
J 0
(8585 2105);
DISPLAY 0.489362 (8585 2105);
PAINT MONO (8585 2105);
FORCEPROP 1 LASTPIN (8575 1925) $PN 2
J 0
(8585 1905);
DISPLAY 0.489362 (8585 1905);
PAINT MONO (8585 1905);
FORCEPROP 1 LAST VOLTAGE 4V
J 0
(8625 2050);
DISPLAY 0.489362 (8625 2050);
PAINT SKYBLUE (8625 2050);
FORCEPROP 1 LAST VALUE 22UF
J 0
(8625 2100);
DISPLAY 0.489362 (8625 2100);
PAINT SKYBLUE (8625 2100);
FORCEPROP 1 LAST TOLERANCE 20%
J 0
(8625 2000);
DISPLAY 0.489362 (8625 2000);
PAINT SKYBLUE (8625 2000);
FORCEPROP 1 LAST MATERIAL X6S
J 0
(8625 1950);
DISPLAY 0.489362 (8625 1950);
PAINT SKYBLUE (8625 1950);
FORCEPROP 1 LAST PACK_TYPE C0805
J 0
(8625 1900);
DISPLAY 0.489362 (8625 1900);
PAINT SKYBLUE (8625 1900);
FORCEPROP 2 LAST CDS_LIB pure_quanta
J 0
(8575 2025);
DISPLAY INVISIBLE (8575 2025);
FORCEPROP 1 LAST PATH I67
J 0
(8625 2175);
DISPLAY 0.978723 (8625 2175);
PAINT WHITE (8625 2175);
DISPLAY INVISIBLE (8625 2175);
FORCEPROP 1 LAST PART_NUMBER CH622KMEA03
J 0
(8625 1850);
DISPLAY 0.489362 (8625 1850);
PAINT SKYBLUE (8625 1850);
DISPLAY INVISIBLE (8625 1850);
FORCEADD VCC_CORE..1
(8575 2375);
FORCEPROP 3 LASTPIN (8575 2325) SIG_NAME PVDDCR_CPU1_P1\g
J 0
(8585 2335);
DISPLAY 0.659574 (8585 2335);
PAINT MONO (8585 2335);
DISPLAY INVISIBLE (8585 2335);
FORCEPROP 1 LAST HDL_POWER PVDDCR_CPU1_P1
J 1
(8575 2425);
DISPLAY 0.489362 (8575 2425);
PAINT GREEN (8575 2425);
FORCEPROP 2 LAST CDS_LIB pure_quanta_power
J 0
(8575 2375);
DISPLAY INVISIBLE (8575 2375);
FORCEPROP 1 LAST PATH I68
J 0
(8625 2400);
DISPLAY 0.872340 (8625 2400);
PAINT AQUA (8625 2400);
DISPLAY INVISIBLE (8625 2400);
FORCEADD UNIVERSAL_GND..1
(8525 4300);
FORCEPROP 3 LASTPIN (8525 4350) SIG_NAME GND\g
J 0
(8535 4360);
DISPLAY 0.659574 (8535 4360);
PAINT MONO (8535 4360);
DISPLAY INVISIBLE (8535 4360);
FORCEPROP 2 LAST CDS_LIB pure_quanta_power
J 0
(8525 4300);
PAINT MONO (8525 4300);
DISPLAY INVISIBLE (8525 4300);
FORCEPROP 1 LAST HDL_POWER GND
J 1
(8550 4225);
DISPLAY 0.872340 (8550 4225);
PAINT GREEN (8550 4225);
DISPLAY INVISIBLE (8550 4225);
FORCEPROP 1 LAST PATH I69
J 0
(8600 4300);
DISPLAY 0.872340 (8600 4300);
PAINT AQUA (8600 4300);
DISPLAY INVISIBLE (8600 4300);
FORCEADD OFFPAGE..5
(1750 2225);
FORCEPROP 2 LAST $XR0 217 
J 0
(1495 2225);
DISPLAY 0.638298 (1495 2225);
PAINT MONO (1495 2225);
FORCEPROP 2 LAST CDS_LIB standard
J 0
(1750 2225);
DISPLAY INVISIBLE (1750 2225);
FORCEPROP 1 LAST OFFPAGE TRUE
J 0
(2075 2100);
DISPLAY 0.872340 (2075 2100);
PAINT GREEN (2075 2100);
DISPLAY INVISIBLE (2075 2100);
FORCEPROP 1 LAST COMMENT_BODY TRUE
J 0
(1850 2150);
DISPLAY 0.872340 (1850 2150);
PAINT GREEN (1850 2150);
DISPLAY INVISIBLE (1850 2150);
FORCEPROP 2 LAST PATH I7
J 0
(1500 2275);
DISPLAY 0.680851 (1500 2275);
DISPLAY INVISIBLE (1500 2275);
FORCEADD Q_CAP..1
(8100 4650);
FORCEPROP 1 LAST LOCATION PC430_5
J 0
(8150 4775);
DISPLAY 0.489362 (8150 4775);
PAINT SKYBLUE (8150 4775);
FORCEPROP 0 LAST $SEC 1
J 0
(8150 4825);
DISPLAY 0.680851 (8150 4825);
PAINT MONO (8150 4825);
DISPLAY INVISIBLE (8150 4825);
FORCEPROP 0 LAST CDS_SEC 1
J 0
(8150 4825);
DISPLAY 1.021277 (8150 4825);
DISPLAY INVISIBLE (8150 4825);
FORCEPROP 1 LASTPIN (8100 4750) $PN 1
J 0
(8110 4730);
DISPLAY 0.489362 (8110 4730);
PAINT MONO (8110 4730);
FORCEPROP 1 LASTPIN (8100 4550) $PN 2
J 0
(8110 4530);
DISPLAY 0.489362 (8110 4530);
PAINT MONO (8110 4530);
FORCEPROP 1 LAST MATERIAL X6S
J 0
(8150 4575);
DISPLAY 0.489362 (8150 4575);
PAINT SKYBLUE (8150 4575);
FORCEPROP 1 LAST TOLERANCE 20%
J 0
(8150 4625);
DISPLAY 0.489362 (8150 4625);
PAINT SKYBLUE (8150 4625);
FORCEPROP 1 LAST VALUE 22UF
J 0
(8150 4725);
DISPLAY 0.489362 (8150 4725);
PAINT SKYBLUE (8150 4725);
FORCEPROP 1 LAST VOLTAGE 4V
J 0
(8150 4675);
DISPLAY 0.489362 (8150 4675);
PAINT SKYBLUE (8150 4675);
FORCEPROP 1 LAST PACK_TYPE C0805
J 0
(8150 4525);
DISPLAY 0.489362 (8150 4525);
PAINT SKYBLUE (8150 4525);
FORCEPROP 2 LAST CDS_LIB pure_quanta
J 0
(8100 4650);
DISPLAY INVISIBLE (8100 4650);
FORCEPROP 1 LAST PATH I70
J 0
(8150 4800);
DISPLAY 0.978723 (8150 4800);
PAINT WHITE (8150 4800);
DISPLAY INVISIBLE (8150 4800);
FORCEPROP 1 LAST PART_NUMBER CH622KMEA03
J 0
(8150 4475);
DISPLAY 0.489362 (8150 4475);
PAINT SKYBLUE (8150 4475);
DISPLAY INVISIBLE (8150 4475);
FORCEADD Q_CAP..1
(8525 4650);
FORCEPROP 1 LAST LOCATION PC431_5
J 0
(8575 4775);
DISPLAY 0.489362 (8575 4775);
PAINT SKYBLUE (8575 4775);
FORCEPROP 0 LAST $SEC 1
J 0
(8575 4825);
DISPLAY 0.680851 (8575 4825);
PAINT MONO (8575 4825);
DISPLAY INVISIBLE (8575 4825);
FORCEPROP 0 LAST CDS_SEC 1
J 0
(8575 4825);
DISPLAY 1.021277 (8575 4825);
DISPLAY INVISIBLE (8575 4825);
FORCEPROP 1 LASTPIN (8525 4750) $PN 1
J 0
(8535 4730);
DISPLAY 0.489362 (8535 4730);
PAINT MONO (8535 4730);
FORCEPROP 1 LASTPIN (8525 4550) $PN 2
J 0
(8535 4530);
DISPLAY 0.489362 (8535 4530);
PAINT MONO (8535 4530);
FORCEPROP 1 LAST VOLTAGE 4V
J 0
(8575 4675);
DISPLAY 0.489362 (8575 4675);
PAINT SKYBLUE (8575 4675);
FORCEPROP 1 LAST VALUE 22UF
J 0
(8575 4725);
DISPLAY 0.489362 (8575 4725);
PAINT SKYBLUE (8575 4725);
FORCEPROP 1 LAST TOLERANCE 20%
J 0
(8575 4625);
DISPLAY 0.489362 (8575 4625);
PAINT SKYBLUE (8575 4625);
FORCEPROP 1 LAST MATERIAL X6S
J 0
(8575 4575);
DISPLAY 0.489362 (8575 4575);
PAINT SKYBLUE (8575 4575);
FORCEPROP 1 LAST PACK_TYPE C0805
J 0
(8575 4525);
DISPLAY 0.489362 (8575 4525);
PAINT SKYBLUE (8575 4525);
FORCEPROP 2 LAST CDS_LIB pure_quanta
J 0
(8525 4650);
DISPLAY INVISIBLE (8525 4650);
FORCEPROP 1 LAST PATH I71
J 0
(8575 4800);
DISPLAY 0.978723 (8575 4800);
PAINT WHITE (8575 4800);
DISPLAY INVISIBLE (8575 4800);
FORCEPROP 1 LAST PART_NUMBER CH622KMEA03
J 0
(8575 4475);
DISPLAY 0.489362 (8575 4475);
PAINT SKYBLUE (8575 4475);
DISPLAY INVISIBLE (8575 4475);
FORCEADD VCC_CORE..1
(8525 5000);
FORCEPROP 3 LASTPIN (8525 4950) SIG_NAME PVDDCR_CPU1_P1\g
J 0
(8535 4960);
DISPLAY 0.659574 (8535 4960);
PAINT MONO (8535 4960);
DISPLAY INVISIBLE (8535 4960);
FORCEPROP 1 LAST HDL_POWER PVDDCR_CPU1_P1
J 1
(8525 5050);
DISPLAY 0.489362 (8525 5050);
PAINT GREEN (8525 5050);
FORCEPROP 2 LAST CDS_LIB pure_quanta_power
J 0
(8525 5000);
DISPLAY INVISIBLE (8525 5000);
FORCEPROP 1 LAST PATH I72
J 0
(8575 5025);
DISPLAY 0.872340 (8575 5025);
PAINT AQUA (8575 5025);
DISPLAY INVISIBLE (8575 5025);
FORCEADD ISL99390FRZTR5935..1
(3150 4850);
FORCEPROP 1 LAST LOCATION PU38
J 0
(2850 5725);
DISPLAY 0.489362 (2850 5725);
PAINT SKYBLUE (2850 5725);
FORCEPROP 2 LAST $SEC 1
J 0
(2850 5900);
DISPLAY 0.680851 (2850 5900);
PAINT MONO (2850 5900);
DISPLAY INVISIBLE (2850 5900);
FORCEPROP 2 LAST CDS_SEC 1
J 0
(2850 5900);
DISPLAY 1.021277 (2850 5900);
DISPLAY INVISIBLE (2850 5900);
FORCEPROP 2 LASTPIN (3550 4400) $PN 2
J 0
(3560 4410);
DISPLAY 0.489362 (3560 4410);
PAINT MONO (3560 4410);
FORCEPROP 2 LASTPIN (3550 5200) $PN 33
J 0
(3560 5210);
DISPLAY 0.489362 (3560 5210);
PAINT MONO (3560 5210);
FORCEPROP 2 LASTPIN (2700 4600) $PN 31
J 2
(2690 4610);
DISPLAY 0.489362 (2690 4610);
PAINT MONO (2690 4610);
FORCEPROP 2 LASTPIN (2700 5000) $PN 35
J 2
(2690 5010);
DISPLAY 0.489362 (2690 5010);
PAINT MONO (2690 5010);
FORCEPROP 2 LASTPIN (3550 4550) $PN 6
J 0
(3560 4560);
DISPLAY 0.489362 (3560 4560);
PAINT MONO (3560 4560);
FORCEPROP 2 LASTPIN (3550 4500) $PN 41
J 0
(3560 4510);
DISPLAY 0.489362 (3560 4510);
PAINT MONO (3560 4510);
FORCEPROP 2 LASTPIN (2700 4850) $PN 38
J 2
(2690 4860);
DISPLAY 0.489362 (2690 4860);
PAINT MONO (2690 4860);
FORCEPROP 2 LASTPIN (2700 4550) $PN 37
J 2
(2690 4560);
DISPLAY 0.489362 (2690 4560);
PAINT MONO (2690 4560);
FORCEPROP 2 LASTPIN (3550 4350) $PN 5
J 0
(3560 4360);
DISPLAY 0.489362 (3560 4360);
PAINT MONO (3560 4360);
FORCEPROP 2 LASTPIN (3550 4300) $PN 7_9-20_24
J 0
(3560 4310);
DISPLAY 0.489362 (3560 4310);
PAINT MONO (3560 4310);
FORCEPROP 2 LASTPIN (3550 4250) $PN 40
J 0
(3560 4260);
DISPLAY 0.489362 (3560 4260);
PAINT MONO (3560 4260);
FORCEPROP 2 LASTPIN (3550 4950) $PN 32
J 0
(3560 4960);
DISPLAY 0.489362 (3560 4960);
PAINT MONO (3560 4960);
FORCEPROP 2 LASTPIN (2700 5500) $PN 4
J 2
(2690 5510);
DISPLAY 0.489362 (2690 5510);
PAINT MONO (2690 5510);
FORCEPROP 2 LASTPIN (2700 4250) $PN 34
J 2
(2690 4260);
DISPLAY 0.489362 (2690 4260);
PAINT MONO (2690 4260);
FORCEPROP 2 LASTPIN (2700 4750) $PN 39
J 2
(2690 4760);
DISPLAY 0.489362 (2690 4760);
PAINT MONO (2690 4760);
FORCEPROP 2 LASTPIN (3550 4850) $PN 10_19
J 0
(3560 4860);
DISPLAY 0.489362 (3560 4860);
PAINT MONO (3560 4860);
FORCEPROP 2 LASTPIN (2700 4350) $PN 36
J 2
(2690 4360);
DISPLAY 0.489362 (2690 4360);
PAINT MONO (2690 4360);
FORCEPROP 2 LASTPIN (2700 5200) $PN 3
J 2
(2690 5210);
DISPLAY 0.489362 (2690 5210);
PAINT MONO (2690 5210);
FORCEPROP 2 LASTPIN (3550 5500) $PN 25_29
J 0
(3560 5510);
DISPLAY 0.489362 (3560 5510);
PAINT MONO (3560 5510);
FORCEPROP 2 LASTPIN (3550 5450) $PN 30
J 0
(3560 5460);
DISPLAY 0.489362 (3560 5460);
PAINT MONO (3560 5460);
FORCEPROP 2 LASTPIN (3550 4600) $PN 1
J 0
(3560 4610);
DISPLAY 0.489362 (3560 4610);
PAINT MONO (3560 4610);
FORCEPROP 1 LAST MATERIAL IC
J 0
(2850 5575);
DISPLAY 0.489362 (2850 5575);
PAINT SKYBLUE (2850 5575);
FORCEPROP 2 LAST VALUE ISL99390FRZ-TR5935
J 0
(2850 5825);
DISPLAY 0.489362 (2850 5825);
PAINT SKYBLUE (2850 5825);
FORCEPROP 2 LAST PART_TYPE SMLF
J 0
(2850 5875);
DISPLAY 0.638298 (2850 5875);
FORCEPROP 1 LAST NEEDS_NO_SIZE TRUE
J 0
(3150 4850);
DISPLAY 0.723404 (3150 4850);
PAINT GREEN (3150 4850);
DISPLAY INVISIBLE (3150 4850);
FORCEPROP 1 LAST CDS_LMAN_SYM_OUTLINE -300,700,250,-650
J 0
(3150 4850);
DISPLAY 0.468085 (3150 4850);
PAINT GREEN (3150 4850);
DISPLAY INVISIBLE (3150 4850);
FORCEPROP 2 LAST CDS_LIB pure_quanta
J 0
(3150 4850);
DISPLAY INVISIBLE (3150 4850);
FORCEPROP 1 LAST PATH I73
J 0
(3150 4850);
DISPLAY 0.723404 (3150 4850);
PAINT GREEN (3150 4850);
DISPLAY INVISIBLE (3150 4850);
FORCEPROP 1 LAST PART_NUMBER AL099390004
J 0
(2850 5650);
DISPLAY 0.489362 (2850 5650);
PAINT SKYBLUE (2850 5650);
DISPLAY INVISIBLE (2850 5650);
FORCEADD OFFPAGE..1
(1750 2125);
FORCEPROP 2 LAST $XR5 223 
J 0
(898 2125);
DISPLAY 0.638298 (898 2125);
PAINT MONO (898 2125);
FORCEPROP 2 LAST $XR4 222 
J 0
(1018 2125);
DISPLAY 0.638298 (1018 2125);
PAINT MONO (1018 2125);
FORCEPROP 2 LAST $XR3 220 
J 0
(1138 2125);
DISPLAY 0.638298 (1138 2125);
PAINT MONO (1138 2125);
FORCEPROP 2 LAST $XR2 219 
J 0
(1258 2125);
DISPLAY 0.638298 (1258 2125);
PAINT MONO (1258 2125);
FORCEPROP 2 LAST $XR1 218 
J 0
(1378 2125);
DISPLAY 0.638298 (1378 2125);
PAINT MONO (1378 2125);
FORCEPROP 2 LAST $XR0 217 
J 0
(1498 2125);
DISPLAY 0.638298 (1498 2125);
PAINT MONO (1498 2125);
FORCEPROP 2 LAST CDS_LIB standard
J 0
(1750 2125);
DISPLAY INVISIBLE (1750 2125);
FORCEPROP 1 LAST OFFPAGE TRUE
J 0
(2075 2000);
DISPLAY 0.872340 (2075 2000);
PAINT GREEN (2075 2000);
DISPLAY INVISIBLE (2075 2000);
FORCEPROP 1 LAST COMMENT_BODY TRUE
J 0
(1875 2025);
DISPLAY 0.872340 (1875 2025);
PAINT GREEN (1875 2025);
DISPLAY INVISIBLE (1875 2025);
FORCEPROP 2 LAST PATH I8
J 0
(1500 2175);
DISPLAY 0.680851 (1500 2175);
DISPLAY INVISIBLE (1500 2175);
FORCEADD UNIVERSAL_GND..1
(725 4275);
FORCEPROP 3 LASTPIN (725 4325) SIG_NAME GND\g
J 0
(735 4335);
DISPLAY 0.659574 (735 4335);
PAINT MONO (735 4335);
DISPLAY INVISIBLE (735 4335);
FORCEPROP 2 LAST CDS_LIB pure_quanta_power
J 0
(725 4275);
DISPLAY INVISIBLE (725 4275);
FORCEPROP 1 LAST HDL_POWER GND
J 1
(750 4200);
DISPLAY 0.872340 (750 4200);
PAINT GREEN (750 4200);
DISPLAY INVISIBLE (750 4200);
FORCEPROP 1 LAST PATH I9
J 0
(800 4275);
DISPLAY 0.872340 (800 4275);
PAINT AQUA (800 4275);
DISPLAY INVISIBLE (800 4275);
FORCEADD DNS..1
(4625 4650);
PAINT RED (4625 4650);
FORCEPROP 2 LAST CDS_LIB mstr_misc
J 0
(4625 4650);
DISPLAY INVISIBLE (4625 4650);
FORCEPROP 1 LAST COMMENT_BODY TRUE
R 1
J 0
(4700 4425);
DISPLAY 0.872340 (4700 4425);
PAINT GREEN (4700 4425);
DISPLAY INVISIBLE (4700 4425);
FORCEADD DNS..1
(4625 4175);
PAINT RED (4625 4175);
FORCEPROP 2 LAST CDS_LIB mstr_misc
J 0
(4625 4175);
DISPLAY INVISIBLE (4625 4175);
FORCEPROP 1 LAST COMMENT_BODY TRUE
R 1
J 0
(4700 3950);
DISPLAY 0.872340 (4700 3950);
PAINT GREEN (4700 3950);
DISPLAY INVISIBLE (4700 3950);
FORCEADD DNS..1
(4700 2025);
PAINT RED (4700 2025);
FORCEPROP 2 LAST CDS_LIB mstr_misc
J 0
(4700 2025);
DISPLAY INVISIBLE (4700 2025);
FORCEPROP 1 LAST COMMENT_BODY TRUE
R 1
J 0
(4775 1800);
DISPLAY 0.872340 (4775 1800);
PAINT GREEN (4775 1800);
DISPLAY INVISIBLE (4775 1800);
FORCEADD DNS..1
(4700 1500);
PAINT RED (4700 1500);
FORCEPROP 2 LAST CDS_LIB mstr_misc
J 0
(4700 1500);
DISPLAY INVISIBLE (4700 1500);
FORCEPROP 1 LAST COMMENT_BODY TRUE
R 1
J 0
(4775 1275);
DISPLAY 0.872340 (4775 1275);
PAINT GREEN (4775 1275);
DISPLAY INVISIBLE (4775 1275);
FORCEADD DNS..1
(1225 4325);
PAINT RED (1225 4325);
FORCEPROP 2 LAST CDS_LIB mstr_misc
J 0
(1225 4325);
PAINT MONO (1225 4325);
DISPLAY INVISIBLE (1225 4325);
FORCEPROP 1 LAST COMMENT_BODY TRUE
R 1
J 0
(1300 4100);
DISPLAY 0.872340 (1300 4100);
PAINT GREEN (1300 4100);
DISPLAY INVISIBLE (1300 4100);
FORCEADD DNS..1
(1275 1700);
PAINT RED (1275 1700);
FORCEPROP 2 LAST CDS_LIB mstr_misc
J 0
(1275 1700);
PAINT MONO (1275 1700);
DISPLAY INVISIBLE (1275 1700);
FORCEPROP 1 LAST COMMENT_BODY TRUE
R 1
J 0
(1350 1475);
DISPLAY 0.872340 (1350 1475);
PAINT GREEN (1350 1475);
DISPLAY INVISIBLE (1350 1475);
FORCEADD QUANTA_TITLE_BLOCK_C..1
(9400 100);
FORCEPROP 0 LAST CDS_CON_LAST_MODIFIED Thu Sep 14 16:12:21 2023
J 0
(7515 115);
DISPLAY INVISIBLE (7515 115);
FORCEPROP 1 LAST CUSTOM_TXT_CDS <CON_LAST_MODIFIED>
J 0
(7515 115);
DISPLAY 0.978723 (7515 115);
FORCEPROP 2 LAST CUSTOM_TXT_CDS <XR_PAGE_TITLE>
J 0
(1510 5350);
DISPLAY 0.638298 (1510 5350);
PAINT PINK (1510 5350);
DISPLAY INVISIBLE (1510 5350);
FORCEPROP 1 LAST CUSTOM_TXT_CDS <NAME_2>
J 0
(6225 150);
FORCEPROP 1 LAST CUSTOM_TXT_CDS <NAME_1>
J 0
(6225 275);
FORCEPROP 1 LAST CUSTOM_TXT_CDS <Q_NUMBER>
J 0
(7997 203);
DISPLAY 1.212766 (7997 203);
FORCEPROP 1 LAST CUSTOM_TXT_CDS <Q_PROJ>
J 0
(7018 202);
DISPLAY 1.212766 (7018 202);
FORCEPROP 1 LAST CUSTOM_TXT_CDS <Q_REV>
J 0
(9216 203);
DISPLAY 1.212766 (9216 203);
FORCEPROP 1 LAST CUSTOM_TXT_CDS <CON_PAGE_NUM> OF <CON_TOTAL_PAGES>
J 0
(8954 118);
DISPLAY 0.978723 (8954 118);
FORCEPROP 1 LAST Q_TITLE PVDDCR_CPU1_P1 VR PHASE 5&6
J 0
(100 175);
DISPLAY 2.446809 (100 175);
PAINT GREEN (100 175);
FORCEPROP 2 LAST CDS_LIB pure_quanta
J 0
(9400 100);
DISPLAY INVISIBLE (9400 100);
FORCEPROP 1 LAST CDS_LMAN_SYM_OUTLINE -9475,6775,100,-125
J 0
(9400 100);
DISPLAY 0.468085 (9400 100);
PAINT GREEN (9400 100);
DISPLAY INVISIBLE (9400 100);
FORCEPROP 2 LAST PAGE_BORDER TRUE
J 0
(1510 5350);
DISPLAY 0.638298 (1510 5350);
PAINT PINK (1510 5350);
DISPLAY INVISIBLE (1510 5350);
FORCEPROP 2 LAST CDS_XR_PAGE_TITLE CR-220 : @T6G_MB_LIB.T6G(SCH_1):PAGE220
J 0
(1510 5350);
DISPLAY 0.638298 (1510 5350);
PAINT PINK (1510 5350);
DISPLAY INVISIBLE (1510 5350);
FORCEPROP 1 LAST Q_DEPT BU9
J 1
(5637 149);
DISPLAY 1.957447 (5637 149);
PAINT GREEN (5637 149);
DISPLAY INVISIBLE (5637 149);
FORCEPROP 1 LAST COMMENT_BODY TRUE
J 0
(9412 87);
DISPLAY 0.978723 (9412 87);
PAINT GREEN (9412 87);
DISPLAY INVISIBLE (9412 87);
WIRE 16 -1 (1725 2550)(1725 2500);
WIRE 16 -1 (1225 4250)(1225 4175);
WIRE 16 -1 (775 1700)(775 1750);
WIRE 16 -1 (2075 3125)(2075 3000);
WIRE 16 -1 (1675 5175)(1675 5125);
WIRE 16 -1 (1275 1625)(1275 1550);
WIRE 16 -1 (2025 5750)(2025 5625);
WIRE 16 -1 (4725 1400)(4725 1325);
WIRE 16 -1 (5475 1975)(5375 1975);
WIRE 16 -1 (5375 1975)(5375 1925);
WIRE 16 -1 (4650 4075)(4650 4000);
WIRE 16 -1 (725 4325)(725 4375);
WIRE 16 -1 (4725 2125)(4725 2225);
WIRE 16 -1 (4725 2225)(6250 2225);
WIRE 16 -1 (3600 2225)(4725 2225);
FORCEPROP 2 LAST SIG_NAME SW_PVDDCR_CPU1_P1_SW6
J 0
(3790 2235);
DISPLAY 0.489362 (3790 2235);
FORCEPROP 2 LASTPROP $XRERR UNIQUE?
J 0
(3550 2235);
DISPLAY 0.638298 (3550 2235);
PAINT MONO (3550 2235);
DISPLAY INVISIBLE (3550 2235);
WIRE 16 -1 (5650 1075)(4425 1075);
FORCEPROP 2 LAST SIG_NAME PVDDCR_CPU1_P1_VOS6
J 0
(3715 2000);
DISPLAY 0.489362 (3715 2000);
FORCEPROP 2 LASTPROP $XRERR UNIQUE?
J 0
(3475 2000);
DISPLAY 0.638298 (3475 2000);
PAINT MONO (3475 2000);
DISPLAY INVISIBLE (3475 2000);
WIRE 16 -1 (4425 1975)(4425 1075);
WIRE 16 -1 (3600 1975)(4425 1975);
WIRE 16 -1 (5650 3025)(5650 2875);
WIRE 16 -1 (5650 2825)(5650 2875);
WIRE 16 -1 (5275 2875)(5650 2875);
WIRE 16 -1 (5275 3025)(5275 2875);
WIRE 16 -1 (4875 2875)(5275 2875);
WIRE 16 -1 (4875 3025)(4875 2875);
WIRE 16 -1 (4875 2875)(4475 2875);
WIRE 16 -1 (4475 3025)(4475 2875);
WIRE 16 -1 (4050 2875)(4475 2875);
WIRE 16 -1 (4050 3025)(4050 2875);
WIRE 16 -1 (3600 2825)(3775 2825);
WIRE 16 -1 (3775 2825)(3775 2875);
WIRE 16 -1 (3775 3375)(3775 2875);
WIRE 16 -1 (3600 2875)(3775 2875);
WIRE 16 -1 (4050 3375)(3775 3375);
WIRE 16 -1 (4475 3375)(4050 3375);
WIRE 16 -1 (4050 3225)(4050 3375);
WIRE 16 -1 (4475 3375)(4875 3375);
WIRE 16 -1 (4475 3225)(4475 3375);
WIRE 16 -1 (4875 3375)(5275 3375);
WIRE 16 -1 (4875 3375)(4875 3225);
WIRE 16 -1 (5275 3375)(5650 3375);
WIRE 16 -1 (5275 3225)(5275 3375);
WIRE 16 -1 (5650 3425)(5650 3375);
WIRE 16 -1 (5650 3225)(5650 3375);
WIRE 16 -1 (3550 4600)(4375 4600);
WIRE 16 -1 (4375 4600)(4375 3800);
WIRE 16 -1 (5475 3800)(4375 3800);
FORCEPROP 2 LAST SIG_NAME PVDDCR_CPU1_P1_VOS5
J 0
(3665 4625);
DISPLAY 0.489362 (3665 4625);
FORCEPROP 2 LASTPROP $XRERR UNIQUE?
J 0
(3425 4625);
DISPLAY 0.638298 (3425 4625);
PAINT MONO (3425 4625);
DISPLAY INVISIBLE (3425 4625);
WIRE 16 -1 (4650 4750)(4650 4850);
WIRE 16 -1 (4650 4850)(6200 4850);
WIRE 16 -1 (3550 4850)(4650 4850);
FORCEPROP 2 LAST SIG_NAME SW_PVDDCR_CPU1_P1_SW5
J 0
(3740 4860);
DISPLAY 0.489362 (3740 4860);
FORCEPROP 2 LASTPROP $XRERR UNIQUE?
J 0
(3500 4860);
DISPLAY 0.638298 (3500 4860);
PAINT MONO (3500 4860);
DISPLAY INVISIBLE (3500 4860);
WIRE 16 -1 (5400 4950)(5400 4975);
WIRE 16 -1 (3550 4950)(5400 4950);
FORCEPROP 2 LAST SIG_NAME SW_PVDDCR_CPU1_P1_BOOTR5
J 0
(3740 4960);
DISPLAY 0.489362 (3740 4960);
FORCEPROP 2 LASTPROP $XRERR UNIQUE?
J 0
(3500 4960);
DISPLAY 0.638298 (3500 4960);
PAINT MONO (3500 4960);
DISPLAY INVISIBLE (3500 4960);
WIRE 16 -1 (5600 5650)(5600 5500);
WIRE 16 -1 (5600 5450)(5600 5500);
WIRE 16 -1 (5225 5500)(5600 5500);
WIRE 16 -1 (5225 5650)(5225 5500);
WIRE 16 -1 (4825 5500)(5225 5500);
WIRE 16 -1 (4825 5650)(4825 5500);
WIRE 16 -1 (4825 5500)(4425 5500);
WIRE 16 -1 (4425 5650)(4425 5500);
WIRE 16 -1 (4000 5500)(4425 5500);
WIRE 16 -1 (4000 5650)(4000 5500);
WIRE 16 -1 (5400 5200)(5400 5175);
WIRE 16 -1 (4600 5200)(5400 5200);
FORCEPROP 2 LAST SIG_NAME SW_PVDDCR_CPU1_P1_BOOT5_R
J 0
(4765 5210);
DISPLAY 0.489362 (4765 5210);
FORCEPROP 2 LASTPROP $XRERR UNIQUE?
J 0
(4525 5210);
DISPLAY 0.638298 (4525 5210);
PAINT MONO (4525 5210);
DISPLAY INVISIBLE (4525 5210);
WIRE 16 -1 (3550 5200)(4400 5200);
FORCEPROP 2 LAST SIG_NAME SW_PVDDCR_CPU1_P1_BOOT5
J 0
(3765 5210);
DISPLAY 0.489362 (3765 5210);
FORCEPROP 2 LASTPROP $XRERR UNIQUE?
J 0
(3525 5210);
DISPLAY 0.638298 (3525 5210);
PAINT MONO (3525 5210);
DISPLAY INVISIBLE (3525 5210);
WIRE 16 -1 (3600 2575)(4450 2575);
FORCEPROP 2 LAST SIG_NAME SW_PVDDCR_CPU1_P1_BOOT6
J 0
(3815 2585);
DISPLAY 0.489362 (3815 2585);
FORCEPROP 2 LASTPROP $XRERR UNIQUE?
J 0
(3575 2585);
DISPLAY 0.638298 (3575 2585);
PAINT MONO (3575 2585);
DISPLAY INVISIBLE (3575 2585);
WIRE 16 -1 (5450 2575)(5450 2550);
WIRE 16 -1 (4650 2575)(5450 2575);
FORCEPROP 2 LAST SIG_NAME SW_PVDDCR_CPU1_P1_BOOT6_R
J 0
(4815 2585);
DISPLAY 0.489362 (4815 2585);
FORCEPROP 2 LASTPROP $XRERR UNIQUE?
J 0
(4575 2585);
DISPLAY 0.638298 (4575 2585);
PAINT MONO (4575 2585);
DISPLAY INVISIBLE (4575 2585);
WIRE 16 -1 (5450 2325)(5450 2350);
WIRE 16 -1 (3600 2325)(5450 2325);
FORCEPROP 2 LAST SIG_NAME SW_PVDDCR_CPU1_P1_BOOTR6
J 0
(3790 2335);
DISPLAY 0.489362 (3790 2335);
FORCEPROP 2 LASTPROP $XRERR UNIQUE?
J 0
(3550 2335);
DISPLAY 0.638298 (3550 2335);
PAINT MONO (3550 2335);
DISPLAY INVISIBLE (3550 2335);
WIRE 16 -1 (5675 1975)(6250 1975);
WIRE 16 -1 (1725 3300)(1725 3425);
WIRE 16 -1 (2075 3425)(1725 3425);
WIRE 16 -1 (1725 3550)(1725 3425);
WIRE 16 -1 (2400 3425)(2075 3425);
WIRE 16 -1 (2075 3325)(2075 3425);
WIRE 16 -1 (2400 2875)(2400 3425);
WIRE 16 -1 (2750 2875)(2400 2875);
WIRE 16 -1 (3600 1675)(3850 1675);
WIRE 16 -1 (3850 1725)(3850 1675);
WIRE 16 -1 (3850 1675)(3850 1625);
WIRE 16 -1 (3600 1625)(3850 1625);
WIRE 16 -1 (3850 1625)(3850 1550);
WIRE 16 -1 (3850 1775)(3850 1725);
WIRE 16 -1 (3600 1725)(3850 1725);
WIRE 16 -1 (3600 1775)(3850 1775);
WIRE 16 -1 (3550 4300)(3800 4300);
WIRE 16 -1 (3800 4350)(3800 4300);
WIRE 16 -1 (3800 4300)(3800 4250);
WIRE 16 -1 (3550 4250)(3800 4250);
WIRE 16 -1 (3800 4250)(3800 4175);
WIRE 16 -1 (3800 4400)(3800 4350);
WIRE 16 -1 (3550 4350)(3800 4350);
WIRE 16 -1 (3550 4400)(3800 4400);
WIRE 16 -1 (1675 5925)(1675 6050);
WIRE 16 -1 (1675 6175)(1675 6050);
WIRE 16 -1 (2025 6050)(1675 6050);
WIRE 16 -1 (2350 6050)(2025 6050);
WIRE 16 -1 (2025 5950)(2025 6050);
WIRE 16 -1 (2350 5500)(2350 6050);
WIRE 16 -1 (2700 5500)(2350 5500);
WIRE 16 -1 (5600 5850)(5600 6000);
WIRE 16 -1 (5600 6050)(5600 6000);
WIRE 16 -1 (5225 6000)(5600 6000);
WIRE 16 -1 (5225 5850)(5225 6000);
WIRE 16 -1 (4825 6000)(5225 6000);
WIRE 16 -1 (4825 6000)(4825 5850);
WIRE 16 -1 (4425 6000)(4825 6000);
WIRE 16 -1 (4425 5850)(4425 6000);
WIRE 16 -1 (4425 6000)(4000 6000);
WIRE 16 -1 (4000 5850)(4000 6000);
WIRE 16 -1 (4000 6000)(3725 6000);
WIRE 16 -1 (3725 6000)(3725 5500);
WIRE 16 -1 (3725 5450)(3725 5500);
WIRE 16 -1 (3550 5500)(3725 5500);
WIRE 16 -1 (3550 5450)(3725 5450);
WIRE 16 -1 (8575 1925)(8575 1800);
WIRE 16 -1 (8575 1725)(8575 1800);
WIRE 16 -1 (8575 1800)(8150 1800);
WIRE 16 -1 (8150 1800)(8150 1925);
WIRE 16 -1 (8150 2225)(7950 2225);
WIRE 16 -1 (8150 2225)(8575 2225);
WIRE 16 -1 (8150 2225)(8150 2125);
WIRE 16 -1 (7950 2225)(7050 2225);
WIRE 16 -1 (7950 2225)(7950 1075);
WIRE 16 -1 (7950 1075)(5850 1075);
WIRE 16 -1 (8575 2325)(8575 2225);
WIRE 16 -1 (8575 2125)(8575 2225);
WIRE 16 -1 (8525 4550)(8525 4425);
WIRE 16 -1 (8525 4350)(8525 4425);
WIRE 16 -1 (8525 4425)(8100 4425);
WIRE 16 -1 (8100 4425)(8100 4550);
WIRE 16 -1 (8100 4850)(7900 4850);
WIRE 16 -1 (8100 4850)(8525 4850);
WIRE 16 -1 (8100 4850)(8100 4750);
WIRE 16 -1 (7900 4850)(7000 4850);
WIRE 16 -1 (7900 4850)(7900 3800);
WIRE 16 -1 (7900 3800)(5675 3800);
WIRE 16 -1 (8525 4950)(8525 4850);
WIRE 16 -1 (8525 4750)(8525 4850);
WIRE 16 -1 (3550 4550)(4150 4550);
FORCEPROP 2 LAST SIG_NAME NC_PVDDCR_CPU1_P1_GL1_5
J 0
(3665 4560);
DISPLAY 0.489362 (3665 4560);
FORCEPROP 2 LASTPROP $XRERR UNIQUE?
J 0
(4180 4550);
DISPLAY 0.638298 (4180 4550);
PAINT MONO (4180 4550);
DISPLAY INVISIBLE (4180 4550);
WIRE 16 -1 (7000 4600)(7575 4600);
FORCEPROP 2 LAST SIG_NAME IND_CPU1_P1_CPL5
J 0
(7140 4610);
DISPLAY 0.489362 (7140 4610);
WIRE 16 -1 (5700 4600)(6200 4600);
FORCEPROP 2 LAST SIG_NAME IND_CPU1_P1_CPL6
J 0
(5740 4610);
DISPLAY 0.489362 (5740 4610);
WIRE 16 -1 (4650 4550)(4650 4275);
FORCEPROP 2 LAST SIG_NAME SW_PVDDCR_CPU1_P1_SW5_RC
J 0
(4690 4385);
DISPLAY 0.489362 (4690 4385);
FORCEPROP 2 LASTPROP $XRERR UNIQUE?
J 0
(4450 4385);
DISPLAY 0.638298 (4450 4385);
PAINT MONO (4450 4385);
DISPLAY INVISIBLE (4450 4385);
WIRE 16 -1 (7050 1975)(7625 1975);
FORCEPROP 2 LAST SIG_NAME IND_CPU1_P1_CPL6
J 0
(7190 1985);
DISPLAY 0.489362 (7190 1985);
WIRE 16 -1 (4725 1925)(4725 1600);
FORCEPROP 2 LAST SIG_NAME SW_PVDDCR_CPU1_P1_SW6_RC
J 0
(4790 1735);
DISPLAY 0.489362 (4790 1735);
FORCEPROP 2 LASTPROP $XRERR UNIQUE?
J 0
(4550 1735);
DISPLAY 0.638298 (4550 1735);
PAINT MONO (4550 1735);
DISPLAY INVISIBLE (4550 1735);
WIRE 16 -1 (3550 4500)(4150 4500);
FORCEPROP 2 LAST SIG_NAME NC_PVDDCR_CPU1_P1_GL2_5
J 0
(3665 4510);
DISPLAY 0.489362 (3665 4510);
FORCEPROP 2 LASTPROP $XRERR UNIQUE?
J 0
(4180 4500);
DISPLAY 0.638298 (4180 4500);
PAINT MONO (4180 4500);
DISPLAY INVISIBLE (4180 4500);
WIRE 16 -1 (3600 1875)(4200 1875);
FORCEPROP 2 LAST SIG_NAME NC_PVDDCR_CPU1_P1_GL2_6
J 0
(3715 1885);
DISPLAY 0.489362 (3715 1885);
FORCEPROP 2 LASTPROP $XRERR UNIQUE?
J 0
(4230 1875);
DISPLAY 0.638298 (4230 1875);
PAINT MONO (4230 1875);
DISPLAY INVISIBLE (4230 1875);
WIRE 16 -1 (3600 1925)(4200 1925);
FORCEPROP 2 LAST SIG_NAME NC_PVDDCR_CPU1_P1_GL1_6
J 0
(3715 1935);
DISPLAY 0.489362 (3715 1935);
FORCEPROP 2 LASTPROP $XRERR UNIQUE?
J 0
(4230 1925);
DISPLAY 0.638298 (4230 1925);
PAINT MONO (4230 1925);
DISPLAY INVISIBLE (4230 1925);
WIRE 16 -1 (2700 5000)(2600 5000);
WIRE 16 -1 (2600 5000)(2600 5200);
WIRE 16 -1 (2600 5200)(2700 5200);
WIRE 16 -1 (2600 5200)(2000 5200);
FORCEPROP 2 LAST SIG_NAME PVDDCR_CPU1_P1_VCC5
J 0
(2065 5210);
DISPLAY 0.489362 (2065 5210);
FORCEPROP 2 LASTPROP $XRERR UNIQUE?
J 0
(1825 5210);
DISPLAY 0.638298 (1825 5210);
PAINT MONO (1825 5210);
DISPLAY INVISIBLE (1825 5210);
WIRE 16 -1 (2000 5475)(2000 5200);
WIRE 16 -1 (1675 5475)(2000 5475);
WIRE 16 -1 (1675 5725)(1675 5475);
WIRE 16 -1 (1675 5375)(1675 5475);
WIRE 16 -1 (2700 4600)(2325 4600);
FORCEPROP 2 LAST SIG_NAME NC_PVDDCR_CPU1_P1_DNC5
J 0
(2130 4610);
DISPLAY 0.489362 (2130 4610);
FORCEPROP 2 LASTPROP $XRERR UNIQUE?
J 0
(2085 4600);
DISPLAY 0.638298 (2085 4600);
PAINT MONO (2085 4600);
DISPLAY INVISIBLE (2085 4600);
WIRE 16 -1 (2600 4750)(2600 4675);
FORCEPROP 0 LAST CDS_PHYS_NET_NAME PVDDCR_CPU1_P1_VCCS
J 0
(2600 4700);
PAINT MONO (2600 4700);
DISPLAY INVISIBLE (2600 4700);
WIRE 16 -1 (2600 4750)(2700 4750);
WIRE 16 -1 (1750 4750)(2600 4750);
FORCEPROP 2 LAST SIG_NAME PVDDCR_CPU1_P1_VCCS
J 0
(1865 4760);
DISPLAY 0.489362 (1865 4760);
WIRE 16 -1 (2600 4675)(725 4675);
WIRE 16 -1 (725 4675)(725 4575);
WIRE 16 -1 (2700 4850)(1750 4850);
FORCEPROP 2 LAST SIG_NAME PVDDCR_CPU1_P1_IMON5
J 0
(1865 4860);
DISPLAY 0.489362 (1865 4860);
WIRE 16 -1 (1225 4550)(2700 4550);
FORCEPROP 2 LAST SIG_NAME PVDDCR_CPU1_P1_LSET5
J 0
(1740 4560);
DISPLAY 0.489362 (1740 4560);
FORCEPROP 2 LASTPROP $XRERR UNIQUE?
J 0
(1500 4560);
DISPLAY 0.638298 (1500 4560);
PAINT MONO (1500 4560);
DISPLAY INVISIBLE (1500 4560);
WIRE 16 -1 (1225 4550)(1225 4450);
WIRE 16 -1 (2750 2375)(2650 2375);
WIRE 16 -1 (2650 2375)(2650 2575);
WIRE 16 -1 (2650 2575)(2750 2575);
WIRE 16 -1 (2650 2575)(2050 2575);
FORCEPROP 2 LAST SIG_NAME PVDDCR_CPU1_P1_VCC6
J 0
(2115 2585);
DISPLAY 0.489362 (2115 2585);
FORCEPROP 2 LASTPROP $XRERR UNIQUE?
J 0
(1875 2585);
DISPLAY 0.638298 (1875 2585);
PAINT MONO (1875 2585);
DISPLAY INVISIBLE (1875 2585);
WIRE 16 -1 (2050 2850)(2050 2575);
WIRE 16 -1 (1725 2850)(2050 2850);
WIRE 16 -1 (1725 3100)(1725 2850);
WIRE 16 -1 (1725 2750)(1725 2850);
WIRE 16 -1 (2750 1975)(2375 1975);
FORCEPROP 2 LAST SIG_NAME NC_PVDDCR_CPU1_P1_DNC6
J 0
(2180 1985);
DISPLAY 0.489362 (2180 1985);
FORCEPROP 2 LASTPROP $XRERR UNIQUE?
J 0
(2135 1975);
DISPLAY 0.638298 (2135 1975);
PAINT MONO (2135 1975);
DISPLAY INVISIBLE (2135 1975);
WIRE 16 -1 (2750 1625)(1800 1625);
FORCEPROP 2 LAST SIG_NAME PVDDCR_CPU1_P1_PWM6
J 0
(1915 1635);
DISPLAY 0.489362 (1915 1635);
WIRE 16 -1 (2750 2225)(1800 2225);
FORCEPROP 2 LAST SIG_NAME PVDDCR_CPU1_P1_IMON6
J 0
(1915 2235);
DISPLAY 0.489362 (1915 2235);
WIRE 16 -1 (2700 4250)(1750 4250);
FORCEPROP 2 LAST SIG_NAME PVDDCR_CPU1_P1_PWM5
J 0
(1865 4260);
DISPLAY 0.489362 (1865 4260);
WIRE 16 -1 (2700 4350)(1750 4350);
FORCEPROP 2 LAST SIG_NAME PVDDCR_CPU1_P1_TEMP0
J 0
(1865 4360);
DISPLAY 0.489362 (1865 4360);
WIRE 16 -1 (2750 1725)(1800 1725);
FORCEPROP 2 LAST SIG_NAME PVDDCR_CPU1_P1_TEMP0
J 0
(1915 1735);
DISPLAY 0.489362 (1915 1735);
WIRE 16 -1 (2650 2125)(2650 2050);
FORCEPROP 0 LAST CDS_PHYS_NET_NAME PVDDCR_CPU1_P1_VCCS
J 0
(2650 2075);
PAINT MONO (2650 2075);
DISPLAY INVISIBLE (2650 2075);
WIRE 16 -1 (2650 2125)(2750 2125);
WIRE 16 -1 (1800 2125)(2650 2125);
FORCEPROP 2 LAST SIG_NAME PVDDCR_CPU1_P1_VCCS
J 0
(1915 2135);
DISPLAY 0.489362 (1915 2135);
WIRE 16 -1 (2650 2050)(775 2050);
WIRE 16 -1 (775 2050)(775 1950);
WIRE 16 -1 (1275 1925)(2750 1925);
FORCEPROP 2 LAST SIG_NAME PVDDCR_CPU1_P1_LSET6
J 0
(1790 1935);
DISPLAY 0.489362 (1790 1935);
FORCEPROP 2 LASTPROP $XRERR UNIQUE?
J 0
(1550 1935);
DISPLAY 0.638298 (1550 1935);
PAINT MONO (1550 1935);
DISPLAY INVISIBLE (1550 1935);
WIRE 16 -1 (1275 1925)(1275 1825);
DOT 1 (4425 5500);
DOT 1 (3775 2875);
DOT 1 (8525 4850);
DOT 1 (8525 4425);
DOT 1 (8100 4850);
DOT 1 (8575 2225);
DOT 1 (8575 1800);
DOT 1 (8150 2225);
DOT 1 (7900 4850);
DOT 1 (5600 6000);
DOT 1 (5600 5500);
DOT 1 (5225 6000);
DOT 1 (5225 5500);
DOT 1 (4825 6000);
DOT 1 (4425 6000);
DOT 1 (4825 5500);
DOT 1 (4000 6000);
DOT 1 (4650 4850);
DOT 1 (7950 2225);
DOT 1 (5650 3375);
DOT 1 (5275 3375);
DOT 1 (5650 2875);
DOT 1 (5275 2875);
DOT 1 (4050 3375);
DOT 1 (4475 3375);
DOT 1 (4875 3375);
DOT 1 (4875 2875);
DOT 1 (4475 2875);
DOT 1 (4725 2225);
DOT 1 (3725 5500);
DOT 1 (2025 6050);
DOT 1 (2600 5200);
DOT 1 (2600 4750);
DOT 1 (1675 6050);
DOT 1 (1675 5475);
DOT 1 (3800 4350);
DOT 1 (3800 4300);
DOT 1 (3800 4250);
DOT 1 (2075 3425);
DOT 1 (2650 2575);
DOT 1 (3850 1725);
DOT 1 (3850 1675);
DOT 1 (3850 1625);
DOT 1 (2650 2125);
DOT 1 (1725 3425);
DOT 1 (1725 2850);
FORCENOTE
PGL6312.121AHLT
(5450 1925) 0;
DISPLAY LEFT (5450 1925);
DISPLAY 0.638298 (5450 1925);
PAINT WHITE (5450 1925);
FORCENOTE
ISAT:60A@100C
(5450 1875) 0;
DISPLAY LEFT (5450 1875);
DISPLAY 0.638298 (5450 1875);
PAINT WHITE (5450 1875);
FORCENOTE
6.5*6.5*10.0
(5450 1825) 0;
DISPLAY LEFT (5450 1825);
DISPLAY 0.638298 (5450 1825);
PAINT WHITE (5450 1825);
FORCENOTE
DCR=0.17M OHM
(5450 1775) 0;
DISPLAY LEFT (5450 1775);
DISPLAY 0.638298 (5450 1775);
PAINT WHITE (5450 1775);
FORCENOTE
2ND=CV+12^0EZ04 
(5450 1725) 0;
DISPLAY LEFT (5450 1725);
DISPLAY 0.638298 (5450 1725);
PAINT WHITE (5450 1725);
FORCENOTE
PVDDCR_CPU1_P1_PHASE6
(2825 3400) 0;
DISPLAY LEFT (2825 3400);
DISPLAY 1.021277 (2825 3400);
PAINT WHITE (2825 3400);
FORCENOTE
DCR=1-4,0.105M OHM
(7000 5000) 0;
DISPLAY LEFT (7000 5000);
DISPLAY 0.638298 (7000 5000);
PAINT WHITE (7000 5000);
FORCENOTE
DCR=2-3,0.27M OHM
(7000 4950) 0;
DISPLAY LEFT (7000 4950);
DISPLAY 0.638298 (7000 4950);
PAINT WHITE (7000 4950);
FORCENOTE
PGL6303.151HLT
(7000 5150) 0;
DISPLAY LEFT (7000 5150);
DISPLAY 0.638298 (7000 5150);
PAINT WHITE (7000 5150);
FORCENOTE
ISAT:70A@100C
(7000 5100) 0;
DISPLAY LEFT (7000 5100);
DISPLAY 0.638298 (7000 5100);
PAINT WHITE (7000 5100);
FORCENOTE
11.0*7.5*12.5
(7000 5050) 0;
DISPLAY LEFT (7000 5050);
DISPLAY 0.638298 (7000 5050);
PAINT WHITE (7000 5050);
FORCENOTE
2ND=CV+15^0TZ01
(7000 4900) 0;
DISPLAY LEFT (7000 4900);
DISPLAY 0.638298 (7000 4900);
PAINT WHITE (7000 4900);
FORCENOTE
DCR=2-3,0.27M OHM
(7050 2350) 0;
DISPLAY LEFT (7050 2350);
DISPLAY 0.638298 (7050 2350);
PAINT WHITE (7050 2350);
FORCENOTE
PGL6303.151HLT
(7050 2550) 0;
DISPLAY LEFT (7050 2550);
DISPLAY 0.638298 (7050 2550);
PAINT WHITE (7050 2550);
FORCENOTE
ISAT:70A@100C
(7050 2500) 0;
DISPLAY LEFT (7050 2500);
DISPLAY 0.638298 (7050 2500);
PAINT WHITE (7050 2500);
FORCENOTE
11.0*7.5*12.5
(7050 2450) 0;
DISPLAY LEFT (7050 2450);
DISPLAY 0.638298 (7050 2450);
PAINT WHITE (7050 2450);
FORCENOTE
DCR=1-4,0.105M OHM
(7050 2400) 0;
DISPLAY LEFT (7050 2400);
DISPLAY 0.638298 (7050 2400);
PAINT WHITE (7050 2400);
FORCENOTE
2ND=CV+15^0TZ01
(7050 2300) 0;
DISPLAY LEFT (7050 2300);
DISPLAY 0.638298 (7050 2300);
PAINT WHITE (7050 2300);
FORCENOTE
PVDDCR_CPU1_P1_PHASE5
(2775 6025) 0;
DISPLAY LEFT (2775 6025);
DISPLAY 1.021277 (2775 6025);
PAINT WHITE (2775 6025);
QUIT
